FILE_TYPE = MACRO_DRAWING;
SET COLOR_WIRE YELLOW;
SET COLOR_PROP ORANGE;
SET COLOR_DOT WHITE;
SET COLOR_ARC YELLOW;
SET COLOR_BODY GREEN;
SET COLOR_NOTE PURPLE;
SET PROP_DISPLAY VALUE;
SET PAGE_NUMBER P140;
FORCEADD Q_RES..2
(2525 2700);
FORCEPROP 1 LAST PART_NUMBER CS24702JB10
J 0
(2565 2525);
DISPLAY 0.638298 (2565 2525);
DISPLAY INVISIBLE (2565 2525);
FORCEPROP 1 LAST MATERIAL CHIP
J 0
(2565 2625);
DISPLAY 0.638298 (2565 2625);
FORCEPROP 1 LAST VALUE 4.7K
J 0
(2570 2775);
DISPLAY 0.638298 (2570 2775);
FORCEPROP 1 LAST TOLERANCE 5%
J 0
(2570 2725);
DISPLAY 0.638298 (2570 2725);
FORCEPROP 1 LAST WATTAGE 1/16W
J 0
(2565 2675);
DISPLAY 0.638298 (2565 2675);
FORCEPROP 1 LAST PACK_TYPE 0402LF
J 0
(2565 2575);
DISPLAY 0.638298 (2565 2575);
FORCEPROP 1 LAST $LOCATION R2926
J 0
(2570 2825);
DISPLAY 0.978723 (2570 2825);
FORCEPROP 1 LASTPIN (2525 2800) $PN 1
J 0
(2530 2762);
DISPLAY 0.787234 (2530 2762);
PAINT MONO (2530 2762);
FORCEPROP 1 LASTPIN (2525 2600) $PN 2
J 0
(2530 2610);
DISPLAY 0.787234 (2530 2610);
PAINT MONO (2530 2610);
FORCEPROP 1 LAST PATH I121
J 0
(2575 2875);
DISPLAY 0.978723 (2575 2875);
PAINT WHITE (2575 2875);
DISPLAY INVISIBLE (2575 2875);
FORCEPROP 2 LAST CDS_LIB pure_quanta
J 0
(2525 2700);
DISPLAY INVISIBLE (2525 2700);
FORCEPROP 0 LAST CDS_LOCATION R2926
J 0
(2575 2875);
DISPLAY 1.021277 (2575 2875);
DISPLAY INVISIBLE (2575 2875);
FORCEPROP 0 LAST $SEC 1
J 0
(2575 2875);
DISPLAY 0.680851 (2575 2875);
PAINT MONO (2575 2875);
DISPLAY INVISIBLE (2575 2875);
FORCEPROP 0 LAST CDS_SEC 1
J 0
(2575 2875);
DISPLAY 1.021277 (2575 2875);
DISPLAY INVISIBLE (2575 2875);
FORCEADD UNIVERSAL_GND..1
(2525 2475);
FORCEPROP 3 LASTPIN (2525 2525) SIG_NAME GND\g
J 0
(2535 2535);
DISPLAY 0.659574 (2535 2535);
PAINT MONO (2535 2535);
DISPLAY INVISIBLE (2535 2535);
FORCEPROP 1 LAST PATH I122
J 0
(2600 2475);
DISPLAY 0.872340 (2600 2475);
PAINT AQUA (2600 2475);
DISPLAY INVISIBLE (2600 2475);
FORCEPROP 1 LAST HDL_POWER GND
J 1
(2550 2400);
DISPLAY 0.872340 (2550 2400);
PAINT GREEN (2550 2400);
DISPLAY INVISIBLE (2550 2400);
FORCEPROP 2 LAST CDS_LIB logical_power
J 0
(2525 2475);
DISPLAY INVISIBLE (2525 2475);
FORCEADD UNIVERSAL_GND..1
(2625 1350);
FORCEPROP 3 LASTPIN (2625 1400) SIG_NAME GND\g
J 0
(2635 1410);
DISPLAY 0.659574 (2635 1410);
PAINT MONO (2635 1410);
DISPLAY INVISIBLE (2635 1410);
FORCEPROP 2 LAST CDS_LIB logical_power
J 0
(2625 1350);
DISPLAY INVISIBLE (2625 1350);
FORCEPROP 1 LAST HDL_POWER GND
J 1
(2650 1275);
DISPLAY 0.872340 (2650 1275);
PAINT GREEN (2650 1275);
DISPLAY INVISIBLE (2650 1275);
FORCEPROP 1 LAST PATH I125
J 0
(2700 1350);
DISPLAY 0.872340 (2700 1350);
PAINT AQUA (2700 1350);
DISPLAY INVISIBLE (2700 1350);
FORCEADD 74LVC2G17GW..1
(1475 50);
FORCEPROP 1 LAST PART_NUMBER AL2G0017005
J 0
(1300 -725);
DISPLAY 0.723404 (1300 -725);
PAINT GREEN (1300 -725);
DISPLAY INVISIBLE (1300 -725);
FORCEPROP 1 LAST MATERIAL IC
J 0
(1300 -775);
DISPLAY 0.723404 (1300 -775);
PAINT GREEN (1300 -775);
FORCEPROP 2 LAST VALUE 74LVC2G17GW
J 0
(1298 -680);
DISPLAY 1.021277 (1298 -680);
FORCEPROP 2 LAST PART_TYPE SMLF
J 0
(1298 -630);
DISPLAY 1.021277 (1298 -630);
FORCEPROP 1 LAST $LOCATION U196
J 0
(1702 -190);
DISPLAY 0.723404 (1702 -190);
PAINT GREEN (1702 -190);
FORCEPROP 0 LASTPIN (1100 175) $PN 1
J 2
(1090 185);
DISPLAY 0.680851 (1090 185);
PAINT MONO (1090 185);
FORCEPROP 0 LASTPIN (1100 -75) $PN 3
J 2
(1090 -65);
DISPLAY 0.680851 (1090 -65);
PAINT MONO (1090 -65);
FORCEPROP 0 LASTPIN (1850 175) $PN 6
J 0
(1860 185);
DISPLAY 0.680851 (1860 185);
PAINT MONO (1860 185);
FORCEPROP 0 LASTPIN (1850 -75) $PN 4
J 0
(1860 -65);
DISPLAY 0.680851 (1860 -65);
PAINT MONO (1860 -65);
FORCEPROP 0 LASTPIN (1500 -375) $PN 2
R 1
J 2
(1490 -385);
DISPLAY 0.680851 (1490 -385);
PAINT MONO (1490 -385);
FORCEPROP 0 LASTPIN (1500 475) $PN 5
R 1
J 0
(1490 485);
DISPLAY 0.680851 (1490 485);
PAINT MONO (1490 485);
FORCEPROP 1 LAST PATH I127
J 0
(1700 -225);
DISPLAY 0.723404 (1700 -225);
PAINT GREEN (1700 -225);
DISPLAY INVISIBLE (1700 -225);
FORCEPROP 1 LAST CDS_LMAN_SYM_OUTLINE -225,275,225,-275
J 0
(1475 50);
DISPLAY 0.468085 (1475 50);
PAINT GREEN (1475 50);
DISPLAY INVISIBLE (1475 50);
FORCEPROP 1 LAST NEEDS_NO_SIZE TRUE
J 0
(1700 49);
DISPLAY 0.468085 (1700 49);
PAINT GREEN (1700 49);
DISPLAY INVISIBLE (1700 49);
FORCEPROP 2 LAST CDS_LIB pure_quanta
J 0
(1475 50);
DISPLAY INVISIBLE (1475 50);
FORCEPROP 0 LAST CDS_LOCATION U196
J 0
(1725 -150);
DISPLAY 1.021277 (1725 -150);
DISPLAY INVISIBLE (1725 -150);
FORCEPROP 0 LAST $SEC 1
J 0
(1725 -150);
DISPLAY 0.680851 (1725 -150);
PAINT MONO (1725 -150);
DISPLAY INVISIBLE (1725 -150);
FORCEPROP 0 LAST CDS_SEC 1
J 0
(1725 -150);
DISPLAY 1.021277 (1725 -150);
DISPLAY INVISIBLE (1725 -150);
FORCEADD OFFPAGE..2
(3925 600);
FORCEPROP 2 LAST $XR0 142 
J 0
(4114 600);
DISPLAY 0.638298 (4114 600);
PAINT MONO (4114 600);
FORCEPROP 2 LAST PATH I129
J 0
(4125 650);
DISPLAY 1.021277 (4125 650);
DISPLAY INVISIBLE (4125 650);
FORCEPROP 1 LAST OFFPAGE TRUE
J 0
(4250 475);
DISPLAY 0.872340 (4250 475);
PAINT AQUA (4250 475);
DISPLAY INVISIBLE (4250 475);
FORCEPROP 1 LAST COMMENT_BODY TRUE
J 0
(3880 505);
DISPLAY 0.872340 (3880 505);
PAINT GREEN (3880 505);
DISPLAY INVISIBLE (3880 505);
FORCEPROP 2 LAST CDS_LIB standard
J 0
(3925 600);
DISPLAY INVISIBLE (3925 600);
FORCEADD UNIVERSAL_GND..1
(2625 100);
FORCEPROP 3 LASTPIN (2625 150) SIG_NAME GND\g
J 0
(2635 160);
DISPLAY 0.659574 (2635 160);
PAINT MONO (2635 160);
DISPLAY INVISIBLE (2635 160);
FORCEPROP 2 LAST CDS_LIB logical_power
J 0
(2625 100);
DISPLAY INVISIBLE (2625 100);
FORCEPROP 1 LAST HDL_POWER GND
J 1
(2650 25);
DISPLAY 0.872340 (2650 25);
PAINT GREEN (2650 25);
DISPLAY INVISIBLE (2650 25);
FORCEPROP 1 LAST PATH I132
J 0
(2700 100);
DISPLAY 0.872340 (2700 100);
PAINT AQUA (2700 100);
DISPLAY INVISIBLE (2700 100);
FORCEADD UNIVERSAL_POWER..1
(1625 1300);
FORCEPROP 3 LASTPIN (1625 1250) SIG_NAME P3V3_AUX\g
J 0
(1635 1260);
DISPLAY 0.659574 (1635 1260);
PAINT MONO (1635 1260);
DISPLAY INVISIBLE (1635 1260);
FORCEPROP 1 LAST HDL_POWER P3V3_AUX
J 1
(1625 1350);
DISPLAY 0.872340 (1625 1350);
PAINT GREEN (1625 1350);
FORCEPROP 1 LAST PATH I139
J 0
(1675 1325);
DISPLAY 0.872340 (1675 1325);
PAINT AQUA (1675 1325);
DISPLAY INVISIBLE (1675 1325);
FORCEPROP 2 LAST CDS_LIB logical_power
J 0
(1625 1300);
PAINT MONO (1625 1300);
DISPLAY INVISIBLE (1625 1300);
FORCEADD Q_CAP..1
(1625 975);
FORCEPROP 1 LAST PART_NUMBER CH4104K1B00
J 0
(1675 825);
DISPLAY 0.510638 (1675 825);
DISPLAY INVISIBLE (1675 825);
FORCEPROP 1 LAST PACK_TYPE 0402
J 0
(1675 775);
DISPLAY 0.510638 (1675 775);
FORCEPROP 1 LAST VOLTAGE 25V
J 0
(1675 975);
DISPLAY 0.510638 (1675 975);
FORCEPROP 1 LAST MATERIAL X7R
J 0
(1675 875);
DISPLAY 0.510638 (1675 875);
FORCEPROP 1 LAST VALUE 0.1UF
J 0
(1675 1025);
DISPLAY 0.510638 (1675 1025);
FORCEPROP 1 LAST TOLERANCE 10%
J 0
(1675 925);
DISPLAY 0.510638 (1675 925);
FORCEPROP 1 LAST $LOCATION C1770
J 0
(1675 1075);
DISPLAY 0.787234 (1675 1075);
FORCEPROP 1 LASTPIN (1625 1075) $PN 1
J 0
(1635 1055);
DISPLAY 0.787234 (1635 1055);
FORCEPROP 1 LASTPIN (1625 875) $PN 2
J 0
(1635 855);
DISPLAY 0.787234 (1635 855);
FORCEPROP 1 LAST PATH I140
J 0
(1675 1125);
DISPLAY 0.978723 (1675 1125);
PAINT WHITE (1675 1125);
DISPLAY INVISIBLE (1675 1125);
FORCEPROP 2 LAST CDS_LIB pure_quanta
J 2
(1625 975);
PAINT MONO (1625 975);
DISPLAY INVISIBLE (1625 975);
FORCEPROP 2 LAST CDS_LOCATION C1770
J 0
(1675 1175);
DISPLAY 1.021277 (1675 1175);
DISPLAY INVISIBLE (1675 1175);
FORCEPROP 2 LAST $SEC 1
J 0
(1675 1175);
DISPLAY 0.680851 (1675 1175);
PAINT MONO (1675 1175);
DISPLAY INVISIBLE (1675 1175);
FORCEPROP 2 LAST CDS_SEC 1
J 0
(1675 1175);
DISPLAY 1.021277 (1675 1175);
DISPLAY INVISIBLE (1675 1175);
FORCEADD UNIVERSAL_GND..1
(1625 750);
FORCEPROP 3 LASTPIN (1625 800) SIG_NAME GND\g
J 0
(1635 810);
DISPLAY 0.659574 (1635 810);
PAINT MONO (1635 810);
DISPLAY INVISIBLE (1635 810);
FORCEPROP 1 LAST PATH I141
J 0
(1700 750);
DISPLAY 0.872340 (1700 750);
PAINT AQUA (1700 750);
DISPLAY INVISIBLE (1700 750);
FORCEPROP 2 LAST CDS_LIB logical_power
J 0
(1625 750);
PAINT MONO (1625 750);
DISPLAY INVISIBLE (1625 750);
FORCEPROP 1 LAST HDL_POWER GND
J 1
(1650 675);
DISPLAY 0.872340 (1650 675);
PAINT GREEN (1650 675);
DISPLAY INVISIBLE (1650 675);
FORCEADD UNIVERSAL_GND..1
(1500 -550);
FORCEPROP 3 LASTPIN (1500 -500) SIG_NAME GND\g
J 0
(1510 -490);
DISPLAY 0.659574 (1510 -490);
PAINT MONO (1510 -490);
DISPLAY INVISIBLE (1510 -490);
FORCEPROP 1 LAST PATH I142
J 0
(1575 -550);
DISPLAY 0.872340 (1575 -550);
PAINT AQUA (1575 -550);
DISPLAY INVISIBLE (1575 -550);
FORCEPROP 2 LAST CDS_LIB logical_power
J 0
(1500 -550);
DISPLAY INVISIBLE (1500 -550);
FORCEPROP 1 LAST HDL_POWER GND
J 1
(1525 -625);
DISPLAY 0.872340 (1525 -625);
PAINT GREEN (1525 -625);
DISPLAY INVISIBLE (1525 -625);
FORCEADD OFFPAGE..4
R 2
(-250 600);
FORCEPROP 2 LAST $XR0 213 
J 0
(-502 600);
DISPLAY 0.638298 (-502 600);
PAINT MONO (-502 600);
FORCEPROP 2 LAST PATH I146
J 0
(-500 650);
DISPLAY 1.021277 (-500 650);
DISPLAY INVISIBLE (-500 650);
FORCEPROP 1 LAST OFFPAGE TRUE
J 2
(-575 475);
DISPLAY 0.872340 (-575 475);
PAINT GREEN (-575 475);
DISPLAY INVISIBLE (-575 475);
FORCEPROP 1 LAST COMMENT_BODY TRUE
J 2
(-225 500);
DISPLAY 0.872340 (-225 500);
PAINT GREEN (-225 500);
DISPLAY INVISIBLE (-225 500);
FORCEPROP 2 LAST CDS_LIB standard
J 0
(-250 600);
DISPLAY INVISIBLE (-250 600);
FORCEADD Q_RES..2
(2575 850);
FORCEPROP 1 LAST PART_NUMBER CS24702JB10
J 0
(2615 675);
DISPLAY 0.638298 (2615 675);
DISPLAY INVISIBLE (2615 675);
FORCEPROP 1 LAST TOLERANCE 5%
J 0
(2620 875);
DISPLAY 0.638298 (2620 875);
FORCEPROP 1 LAST VALUE 4.7K
J 0
(2620 925);
DISPLAY 0.638298 (2620 925);
FORCEPROP 1 LAST WATTAGE 1/16W
J 0
(2615 825);
DISPLAY 0.638298 (2615 825);
FORCEPROP 1 LAST MATERIAL EMPTY
J 0
(2615 775);
DISPLAY 0.638298 (2615 775);
PAINT RED (2615 775);
FORCEPROP 1 LAST PACK_TYPE 0402LF
J 0
(2615 725);
DISPLAY 0.638298 (2615 725);
FORCEPROP 1 LAST $LOCATION R2912
J 0
(2620 975);
DISPLAY 0.638298 (2620 975);
FORCEPROP 1 LASTPIN (2575 950) $PN 1
J 0
(2580 912);
DISPLAY 0.787234 (2580 912);
FORCEPROP 1 LASTPIN (2575 750) $PN 2
J 0
(2580 760);
DISPLAY 0.787234 (2580 760);
FORCEPROP 2 LAST CDS_LIB pure_quanta
J 0
(2575 850);
PAINT MONO (2575 850);
DISPLAY INVISIBLE (2575 850);
FORCEPROP 1 LAST PATH I147
J 0
(2625 1025);
DISPLAY 0.978723 (2625 1025);
PAINT WHITE (2625 1025);
DISPLAY INVISIBLE (2625 1025);
FORCEPROP 2 LAST CDS_LOCATION R2912
J 0
(2625 1075);
DISPLAY 1.021277 (2625 1075);
DISPLAY INVISIBLE (2625 1075);
FORCEPROP 2 LAST $SEC 1
J 0
(2625 1075);
DISPLAY 0.680851 (2625 1075);
PAINT MONO (2625 1075);
DISPLAY INVISIBLE (2625 1075);
FORCEPROP 2 LAST CDS_SEC 1
J 0
(2625 1075);
DISPLAY 1.021277 (2625 1075);
DISPLAY INVISIBLE (2625 1075);
FORCEADD UNIVERSAL_POWER..1
(2575 1100);
FORCEPROP 3 LASTPIN (2575 1050) SIG_NAME P3V3_AUX\g
J 0
(2585 1060);
DISPLAY 0.659574 (2585 1060);
PAINT MONO (2585 1060);
DISPLAY INVISIBLE (2585 1060);
FORCEPROP 1 LAST HDL_POWER P3V3_AUX
J 1
(2575 1150);
DISPLAY 0.872340 (2575 1150);
PAINT GREEN (2575 1150);
FORCEPROP 2 LAST CDS_LIB logical_power
J 0
(2575 1100);
PAINT MONO (2575 1100);
DISPLAY INVISIBLE (2575 1100);
FORCEPROP 1 LAST PATH I148
J 0
(2625 1125);
DISPLAY 0.872340 (2625 1125);
PAINT AQUA (2625 1125);
DISPLAY INVISIBLE (2625 1125);
FORCEADD Q_RES..2
(2600 2050);
FORCEPROP 1 LAST PART_NUMBER CS24702JB10
J 0
(2640 1875);
DISPLAY 0.638298 (2640 1875);
DISPLAY INVISIBLE (2640 1875);
FORCEPROP 1 LAST MATERIAL EMPTY
J 0
(2640 1975);
DISPLAY 0.638298 (2640 1975);
PAINT RED (2640 1975);
FORCEPROP 1 LAST PACK_TYPE 0402LF
J 0
(2640 1925);
DISPLAY 0.638298 (2640 1925);
FORCEPROP 1 LAST VALUE 4.7K
J 0
(2645 2125);
DISPLAY 0.638298 (2645 2125);
FORCEPROP 1 LAST WATTAGE 1/16W
J 0
(2640 2025);
DISPLAY 0.638298 (2640 2025);
FORCEPROP 1 LAST TOLERANCE 5%
J 0
(2645 2075);
DISPLAY 0.638298 (2645 2075);
FORCEPROP 1 LAST $LOCATION R2911
J 0
(2645 2175);
DISPLAY 0.638298 (2645 2175);
FORCEPROP 1 LASTPIN (2600 2150) $PN 1
J 0
(2605 2112);
DISPLAY 0.787234 (2605 2112);
FORCEPROP 1 LASTPIN (2600 1950) $PN 2
J 0
(2605 1960);
DISPLAY 0.787234 (2605 1960);
FORCEPROP 1 LAST PATH I153
J 0
(2650 2225);
DISPLAY 0.978723 (2650 2225);
PAINT WHITE (2650 2225);
DISPLAY INVISIBLE (2650 2225);
FORCEPROP 2 LAST CDS_LIB pure_quanta
J 0
(2600 2050);
PAINT MONO (2600 2050);
DISPLAY INVISIBLE (2600 2050);
FORCEPROP 2 LAST CDS_LOCATION R2911
J 0
(2650 2275);
DISPLAY 1.021277 (2650 2275);
DISPLAY INVISIBLE (2650 2275);
FORCEPROP 2 LAST $SEC 1
J 0
(2650 2275);
DISPLAY 0.680851 (2650 2275);
PAINT MONO (2650 2275);
DISPLAY INVISIBLE (2650 2275);
FORCEPROP 2 LAST CDS_SEC 1
J 0
(2650 2275);
DISPLAY 1.021277 (2650 2275);
DISPLAY INVISIBLE (2650 2275);
FORCEADD UNIVERSAL_GND..1
(-50 225);
FORCEPROP 3 LASTPIN (-50 275) SIG_NAME GND\g
J 0
(-40 285);
DISPLAY 0.659574 (-40 285);
PAINT MONO (-40 285);
DISPLAY INVISIBLE (-40 285);
FORCEPROP 2 LAST CDS_LIB logical_power
J 0
(-50 225);
DISPLAY INVISIBLE (-50 225);
FORCEPROP 1 LAST HDL_POWER GND
J 1
(-25 150);
DISPLAY 0.872340 (-25 150);
PAINT GREEN (-25 150);
DISPLAY INVISIBLE (-25 150);
FORCEPROP 1 LAST PATH I159
J 0
(25 225);
DISPLAY 0.872340 (25 225);
PAINT AQUA (25 225);
DISPLAY INVISIBLE (25 225);
FORCEADD Q_RES..2
(-50 400);
FORCEPROP 1 LAST PART_NUMBER CS24702JB10
J 0
(-10 225);
DISPLAY 0.638298 (-10 225);
DISPLAY INVISIBLE (-10 225);
FORCEPROP 1 LAST TOLERANCE 5%
J 0
(-5 425);
DISPLAY 0.638298 (-5 425);
FORCEPROP 1 LAST MATERIAL CHIP
J 0
(-10 325);
DISPLAY 0.638298 (-10 325);
FORCEPROP 1 LAST PACK_TYPE 0402LF
J 0
(-10 275);
DISPLAY 0.638298 (-10 275);
FORCEPROP 1 LAST VALUE 4.7K
J 0
(-5 475);
DISPLAY 0.638298 (-5 475);
FORCEPROP 1 LAST WATTAGE 1/16W
J 0
(-10 375);
DISPLAY 0.638298 (-10 375);
FORCEPROP 1 LAST $LOCATION R2937
J 0
(-5 525);
DISPLAY 0.638298 (-5 525);
FORCEPROP 1 LASTPIN (-50 500) $PN 1
J 0
(-45 462);
DISPLAY 0.787234 (-45 462);
FORCEPROP 1 LASTPIN (-50 300) $PN 2
J 0
(-45 310);
DISPLAY 0.787234 (-45 310);
FORCEPROP 2 LAST CDS_LIB pure_quanta
J 0
(-50 400);
PAINT MONO (-50 400);
DISPLAY INVISIBLE (-50 400);
FORCEPROP 1 LAST PATH I160
J 0
(0 575);
DISPLAY 0.978723 (0 575);
PAINT WHITE (0 575);
DISPLAY INVISIBLE (0 575);
FORCEPROP 2 LAST CDS_LOCATION R2937
J 0
(0 625);
DISPLAY 1.021277 (0 625);
DISPLAY INVISIBLE (0 625);
FORCEPROP 2 LAST $SEC 1
J 0
(0 625);
DISPLAY 0.680851 (0 625);
PAINT MONO (0 625);
DISPLAY INVISIBLE (0 625);
FORCEPROP 2 LAST CDS_SEC 1
J 0
(0 625);
DISPLAY 1.021277 (0 625);
DISPLAY INVISIBLE (0 625);
FORCEADD UNIVERSAL_POWER..1
(-75 1125);
FORCEPROP 3 LASTPIN (-75 1075) SIG_NAME P3V3_AUX\g
J 0
(-65 1085);
DISPLAY 0.659574 (-65 1085);
PAINT MONO (-65 1085);
DISPLAY INVISIBLE (-65 1085);
FORCEPROP 1 LAST HDL_POWER P3V3_AUX
J 1
(-75 1175);
DISPLAY 0.872340 (-75 1175);
PAINT GREEN (-75 1175);
FORCEPROP 1 LAST PATH I161
J 0
(-25 1150);
DISPLAY 0.872340 (-25 1150);
PAINT AQUA (-25 1150);
DISPLAY INVISIBLE (-25 1150);
FORCEPROP 2 LAST CDS_LIB logical_power
J 0
(-75 1125);
PAINT MONO (-75 1125);
DISPLAY INVISIBLE (-75 1125);
FORCEADD Q_RES..2
(-75 875);
FORCEPROP 1 LAST PART_NUMBER CS41002FB09
J 0
(-35 750);
DISPLAY 0.510638 (-35 750);
DISPLAY INVISIBLE (-35 750);
FORCEPROP 1 LAST PACK_TYPE 0402LF
J 0
(-35 700);
DISPLAY 0.510638 (-35 700);
FORCEPROP 1 LAST TOLERANCE 1%
J 0
(-30 900);
DISPLAY 0.510638 (-30 900);
FORCEPROP 1 LAST VALUE 100K
J 0
(-30 950);
DISPLAY 0.510638 (-30 950);
FORCEPROP 1 LAST MATERIAL EMPTY
J 0
(-35 800);
DISPLAY 0.510638 (-35 800);
PAINT RED (-35 800);
FORCEPROP 1 LAST WATTAGE 1/16W
J 0
(-35 850);
DISPLAY 0.510638 (-35 850);
FORCEPROP 1 LAST $LOCATION R2936
J 0
(-30 1000);
DISPLAY 0.978723 (-30 1000);
FORCEPROP 1 LASTPIN (-75 975) $PN 1
J 0
(-70 937);
DISPLAY 0.787234 (-70 937);
PAINT MONO (-70 937);
FORCEPROP 1 LASTPIN (-75 775) $PN 2
J 0
(-70 785);
DISPLAY 0.787234 (-70 785);
PAINT MONO (-70 785);
FORCEPROP 1 LAST PATH I162
J 0
(-25 1050);
DISPLAY 0.978723 (-25 1050);
PAINT WHITE (-25 1050);
DISPLAY INVISIBLE (-25 1050);
FORCEPROP 2 LAST CDS_LIB pure_quanta
J 0
(-75 875);
DISPLAY INVISIBLE (-75 875);
FORCEPROP 0 LAST CDS_LOCATION R2936
J 0
(-25 1050);
DISPLAY 1.021277 (-25 1050);
DISPLAY INVISIBLE (-25 1050);
FORCEPROP 0 LAST $SEC 1
J 0
(-25 1050);
DISPLAY 0.680851 (-25 1050);
PAINT MONO (-25 1050);
DISPLAY INVISIBLE (-25 1050);
FORCEPROP 0 LAST CDS_SEC 1
J 0
(-25 1050);
DISPLAY 1.021277 (-25 1050);
DISPLAY INVISIBLE (-25 1050);
FORCEADD UNIVERSAL_POWER..1
(-325 -1050);
FORCEPROP 3 LASTPIN (-325 -1100) SIG_NAME P3V3_AUX\g
J 0
(-315 -1090);
DISPLAY 0.659574 (-315 -1090);
PAINT MONO (-315 -1090);
DISPLAY INVISIBLE (-315 -1090);
FORCEPROP 1 LAST HDL_POWER P3V3_AUX
J 1
(-325 -1000);
DISPLAY 0.872340 (-325 -1000);
PAINT GREEN (-325 -1000);
FORCEPROP 2 LAST CDS_LIB logical_power
J 0
(-325 -1050);
PAINT MONO (-325 -1050);
DISPLAY INVISIBLE (-325 -1050);
FORCEPROP 1 LAST PATH I165
J 0
(-275 -1025);
DISPLAY 0.872340 (-275 -1025);
PAINT AQUA (-275 -1025);
DISPLAY INVISIBLE (-275 -1025);
FORCEADD Q_CAP..1
(-325 -1375);
FORCEPROP 1 LAST PART_NUMBER CH4104K1B00
J 0
(-275 -1525);
DISPLAY 0.510638 (-275 -1525);
DISPLAY INVISIBLE (-275 -1525);
FORCEPROP 1 LAST VALUE 0.1UF
J 0
(-275 -1325);
DISPLAY 0.510638 (-275 -1325);
FORCEPROP 1 LAST VOLTAGE 25V
J 0
(-275 -1375);
DISPLAY 0.510638 (-275 -1375);
FORCEPROP 1 LAST PACK_TYPE 0402
J 0
(-275 -1575);
DISPLAY 0.510638 (-275 -1575);
FORCEPROP 1 LAST MATERIAL X7R
J 0
(-275 -1475);
DISPLAY 0.510638 (-275 -1475);
FORCEPROP 1 LAST TOLERANCE 10%
J 0
(-275 -1425);
DISPLAY 0.510638 (-275 -1425);
FORCEPROP 1 LAST $LOCATION C1803
J 0
(-275 -1275);
DISPLAY 0.787234 (-275 -1275);
FORCEPROP 1 LASTPIN (-325 -1275) $PN 1
J 0
(-315 -1295);
DISPLAY 0.787234 (-315 -1295);
FORCEPROP 1 LASTPIN (-325 -1475) $PN 2
J 0
(-315 -1495);
DISPLAY 0.787234 (-315 -1495);
FORCEPROP 2 LAST CDS_LIB pure_quanta
J 2
(-325 -1375);
PAINT MONO (-325 -1375);
DISPLAY INVISIBLE (-325 -1375);
FORCEPROP 1 LAST PATH I166
J 0
(-275 -1225);
DISPLAY 0.978723 (-275 -1225);
PAINT WHITE (-275 -1225);
DISPLAY INVISIBLE (-275 -1225);
FORCEPROP 2 LAST CDS_LOCATION C1803
J 0
(-275 -1175);
DISPLAY 1.021277 (-275 -1175);
DISPLAY INVISIBLE (-275 -1175);
FORCEPROP 2 LAST $SEC 1
J 0
(-275 -1175);
DISPLAY 0.680851 (-275 -1175);
PAINT MONO (-275 -1175);
DISPLAY INVISIBLE (-275 -1175);
FORCEPROP 2 LAST CDS_SEC 1
J 0
(-275 -1175);
DISPLAY 1.021277 (-275 -1175);
DISPLAY INVISIBLE (-275 -1175);
FORCEADD UNIVERSAL_GND..1
(-325 -1600);
FORCEPROP 3 LASTPIN (-325 -1550) SIG_NAME GND\g
J 0
(-315 -1540);
DISPLAY 0.659574 (-315 -1540);
PAINT MONO (-315 -1540);
DISPLAY INVISIBLE (-315 -1540);
FORCEPROP 2 LAST CDS_LIB logical_power
J 0
(-325 -1600);
PAINT MONO (-325 -1600);
DISPLAY INVISIBLE (-325 -1600);
FORCEPROP 1 LAST HDL_POWER GND
J 1
(-300 -1675);
DISPLAY 0.872340 (-300 -1675);
PAINT GREEN (-300 -1675);
DISPLAY INVISIBLE (-300 -1675);
FORCEPROP 1 LAST PATH I167
J 0
(-250 -1600);
DISPLAY 0.872340 (-250 -1600);
PAINT AQUA (-250 -1600);
DISPLAY INVISIBLE (-250 -1600);
FORCEADD Q_RES..1
(-1575 -1850);
FORCEPROP 1 LAST PART_NUMBER CS00002JB13
J 0
(-1850 -1975);
DISPLAY 0.723404 (-1850 -1975);
PAINT WHITE (-1850 -1975);
DISPLAY INVISIBLE (-1850 -1975);
FORCEPROP 1 LAST PACK_TYPE 0402LF
J 0
(-1575 -1800);
DISPLAY 0.723404 (-1575 -1800);
FORCEPROP 1 LAST MATERIAL CHIP
J 0
(-1725 -1800);
DISPLAY 0.723404 (-1725 -1800);
FORCEPROP 1 LAST VALUE 0
J 2
(-1425 -1850);
DISPLAY 0.723404 (-1425 -1850);
FORCEPROP 1 LAST $LOCATION R3033
J 0
(-1800 -1850);
DISPLAY 0.723404 (-1800 -1850);
FORCEPROP 1 LASTPIN (-1675 -1850) $PN 1
J 0
(-1663 -1838);
DISPLAY 0.787234 (-1663 -1838);
PAINT MONO (-1663 -1838);
FORCEPROP 1 LASTPIN (-1475 -1850) $PN 2
J 0
(-1513 -1838);
DISPLAY 0.787234 (-1513 -1838);
PAINT MONO (-1513 -1838);
FORCEPROP 1 LAST PATH I170
J 0
(-1625 -1700);
DISPLAY 0.978723 (-1625 -1700);
PAINT WHITE (-1625 -1700);
DISPLAY INVISIBLE (-1625 -1700);
FORCEPROP 1 LAST WATTAGE 1/16W
J 2
(-1500 -1925);
DISPLAY 0.723404 (-1500 -1925);
PAINT SKYBLUE (-1500 -1925);
DISPLAY INVISIBLE (-1500 -1925);
FORCEPROP 1 LAST TOLERANCE 5%
J 0
(-1775 -1925);
DISPLAY 0.723404 (-1775 -1925);
PAINT SKYBLUE (-1775 -1925);
DISPLAY INVISIBLE (-1775 -1925);
FORCEPROP 2 LAST CDS_LIB pure_quanta
J 0
(-1575 -1850);
DISPLAY INVISIBLE (-1575 -1850);
FORCEPROP 2 LAST CDS_LOCATION R3033
J 0
(-1625 -1650);
DISPLAY 1.021277 (-1625 -1650);
DISPLAY INVISIBLE (-1625 -1650);
FORCEPROP 2 LAST $SEC 1
J 0
(-1625 -1650);
DISPLAY 0.680851 (-1625 -1650);
PAINT MONO (-1625 -1650);
DISPLAY INVISIBLE (-1625 -1650);
FORCEPROP 2 LAST CDS_SEC 1
J 0
(-1625 -1650);
DISPLAY 1.021277 (-1625 -1650);
DISPLAY INVISIBLE (-1625 -1650);
FORCEADD OFFPAGE..4
R 2
(-2600 -1950);
FORCEPROP 2 LAST $XR1 245 
J 0
(-2972 -1950);
DISPLAY 0.638298 (-2972 -1950);
PAINT MONO (-2972 -1950);
FORCEPROP 2 LAST $XR0 215 
J 0
(-2852 -1950);
DISPLAY 0.638298 (-2852 -1950);
PAINT MONO (-2852 -1950);
FORCEPROP 2 LAST CDS_LIB standard
J 0
(-2600 -1950);
DISPLAY INVISIBLE (-2600 -1950);
FORCEPROP 1 LAST OFFPAGE TRUE
J 2
(-2925 -2075);
DISPLAY 0.872340 (-2925 -2075);
PAINT GREEN (-2925 -2075);
DISPLAY INVISIBLE (-2925 -2075);
FORCEPROP 1 LAST COMMENT_BODY TRUE
J 2
(-2575 -2050);
DISPLAY 0.872340 (-2575 -2050);
PAINT GREEN (-2575 -2050);
DISPLAY INVISIBLE (-2575 -2050);
FORCEPROP 2 LAST PATH I172
J 0
(-2875 -1900);
DISPLAY 1.021277 (-2875 -1900);
DISPLAY INVISIBLE (-2875 -1900);
FORCEADD OFFPAGE..4
R 2
(-2600 -1850);
FORCEPROP 2 LAST $XR0 137 
J 0
(-2852 -1850);
DISPLAY 0.638298 (-2852 -1850);
PAINT MONO (-2852 -1850);
FORCEPROP 2 LAST PATH I173
J 0
(-2875 -1800);
DISPLAY 1.021277 (-2875 -1800);
DISPLAY INVISIBLE (-2875 -1800);
FORCEPROP 2 LAST CDS_LIB standard
J 0
(-2600 -1850);
DISPLAY INVISIBLE (-2600 -1850);
FORCEPROP 1 LAST OFFPAGE TRUE
J 2
(-2925 -1975);
DISPLAY 0.872340 (-2925 -1975);
PAINT GREEN (-2925 -1975);
DISPLAY INVISIBLE (-2925 -1975);
FORCEPROP 1 LAST COMMENT_BODY TRUE
J 2
(-2575 -1950);
DISPLAY 0.872340 (-2575 -1950);
PAINT GREEN (-2575 -1950);
DISPLAY INVISIBLE (-2575 -1950);
FORCEADD UNIVERSAL_POWER..1
(0 0);
FORCEPROP 3 LASTPIN (0 -50) SIG_NAME P3V3_AUX\g
J 0
(10 -40);
DISPLAY 0.659574 (10 -40);
PAINT MONO (10 -40);
DISPLAY INVISIBLE (10 -40);
FORCEPROP 1 LAST HDL_POWER P3V3_AUX
J 1
(0 50);
DISPLAY 0.872340 (0 50);
PAINT GREEN (0 50);
FORCEPROP 2 LAST CDS_LIB logical_power
J 0
(0 0);
PAINT MONO (0 0);
DISPLAY INVISIBLE (0 0);
FORCEPROP 1 LAST PATH I174
J 0
(50 25);
DISPLAY 0.872340 (50 25);
PAINT AQUA (50 25);
DISPLAY INVISIBLE (50 25);
FORCEADD OFFPAGE..4
R 2
(-200 -525);
FORCEPROP 2 LAST $XR0 214 
J 0
(-482 -525);
DISPLAY 0.638298 (-482 -525);
PAINT MONO (-482 -525);
FORCEPROP 2 LAST PATH I177
J 0
(-475 -475);
DISPLAY 1.021277 (-475 -475);
DISPLAY INVISIBLE (-475 -475);
FORCEPROP 1 LAST OFFPAGE TRUE
J 2
(-525 -650);
DISPLAY 0.872340 (-525 -650);
PAINT GREEN (-525 -650);
DISPLAY INVISIBLE (-525 -650);
FORCEPROP 1 LAST COMMENT_BODY TRUE
J 2
(-175 -625);
DISPLAY 0.872340 (-175 -625);
PAINT GREEN (-175 -625);
DISPLAY INVISIBLE (-175 -625);
FORCEPROP 2 LAST CDS_LIB standard
J 0
(-200 -525);
DISPLAY INVISIBLE (-200 -525);
FORCEADD UNIVERSAL_GND..1
(2650 -1025);
FORCEPROP 3 LASTPIN (2650 -975) SIG_NAME GND\g
J 0
(2660 -965);
DISPLAY 0.659574 (2660 -965);
PAINT MONO (2660 -965);
DISPLAY INVISIBLE (2660 -965);
FORCEPROP 2 LAST CDS_LIB logical_power
J 0
(2650 -1025);
DISPLAY INVISIBLE (2650 -1025);
FORCEPROP 1 LAST HDL_POWER GND
J 1
(2675 -1100);
DISPLAY 0.872340 (2675 -1100);
PAINT GREEN (2675 -1100);
DISPLAY INVISIBLE (2675 -1100);
FORCEPROP 1 LAST PATH I178
J 0
(2725 -1025);
DISPLAY 0.872340 (2725 -1025);
PAINT AQUA (2725 -1025);
DISPLAY INVISIBLE (2725 -1025);
FORCEADD OFFPAGE..2
(3975 -525);
FORCEPROP 2 LAST $XR0 142 
J 0
(4164 -525);
DISPLAY 0.638298 (4164 -525);
PAINT MONO (4164 -525);
FORCEPROP 2 LAST CDS_LIB standard
J 0
(3975 -525);
DISPLAY INVISIBLE (3975 -525);
FORCEPROP 2 LAST PATH I180
J 0
(4175 -475);
DISPLAY 1.021277 (4175 -475);
DISPLAY INVISIBLE (4175 -475);
FORCEPROP 1 LAST OFFPAGE TRUE
J 0
(4300 -650);
DISPLAY 0.872340 (4300 -650);
PAINT AQUA (4300 -650);
DISPLAY INVISIBLE (4300 -650);
FORCEPROP 1 LAST COMMENT_BODY TRUE
J 0
(3930 -620);
DISPLAY 0.872340 (3930 -620);
PAINT GREEN (3930 -620);
DISPLAY INVISIBLE (3930 -620);
FORCEADD UNIVERSAL_POWER..1
(2650 -75);
FORCEPROP 3 LASTPIN (2650 -125) SIG_NAME P3V3_AUX\g
J 0
(2660 -115);
DISPLAY 0.659574 (2660 -115);
PAINT MONO (2660 -115);
DISPLAY INVISIBLE (2660 -115);
FORCEPROP 1 LAST HDL_POWER P3V3_AUX
J 1
(2650 -25);
DISPLAY 0.872340 (2650 -25);
PAINT GREEN (2650 -25);
FORCEPROP 1 LAST PATH I183
J 0
(2700 -50);
DISPLAY 0.872340 (2700 -50);
PAINT AQUA (2700 -50);
DISPLAY INVISIBLE (2700 -50);
FORCEPROP 2 LAST CDS_LIB logical_power
J 0
(2650 -75);
PAINT MONO (2650 -75);
DISPLAY INVISIBLE (2650 -75);
FORCEADD UNIVERSAL_GND..1
(25 -900);
FORCEPROP 3 LASTPIN (25 -850) SIG_NAME GND\g
J 0
(35 -840);
DISPLAY 0.659574 (35 -840);
PAINT MONO (35 -840);
DISPLAY INVISIBLE (35 -840);
FORCEPROP 1 LAST HDL_POWER GND
J 1
(50 -975);
DISPLAY 0.872340 (50 -975);
PAINT GREEN (50 -975);
DISPLAY INVISIBLE (50 -975);
FORCEPROP 2 LAST CDS_LIB logical_power
J 0
(25 -900);
DISPLAY INVISIBLE (25 -900);
FORCEPROP 1 LAST PATH I184
J 0
(100 -900);
DISPLAY 0.872340 (100 -900);
PAINT AQUA (100 -900);
DISPLAY INVISIBLE (100 -900);
FORCEADD Q_RES..2
(2650 -325);
FORCEPROP 1 LAST PART_NUMBER CS24702JB10
J 0
(2690 -500);
DISPLAY 0.638298 (2690 -500);
DISPLAY INVISIBLE (2690 -500);
FORCEPROP 1 LAST TOLERANCE 5%
J 0
(2695 -300);
DISPLAY 0.638298 (2695 -300);
FORCEPROP 1 LAST MATERIAL EMPTY
J 0
(2690 -400);
DISPLAY 0.638298 (2690 -400);
PAINT RED (2690 -400);
FORCEPROP 1 LAST WATTAGE 1/16W
J 0
(2690 -350);
DISPLAY 0.638298 (2690 -350);
FORCEPROP 1 LAST VALUE 4.7K
J 0
(2695 -250);
DISPLAY 0.638298 (2695 -250);
FORCEPROP 1 LAST PACK_TYPE 0402LF
J 0
(2690 -450);
DISPLAY 0.638298 (2690 -450);
FORCEPROP 1 LAST $LOCATION R3317
J 0
(2695 -200);
DISPLAY 0.638298 (2695 -200);
FORCEPROP 1 LASTPIN (2650 -225) $PN 1
J 0
(2655 -263);
DISPLAY 0.787234 (2655 -263);
FORCEPROP 1 LASTPIN (2650 -425) $PN 2
J 0
(2655 -415);
DISPLAY 0.787234 (2655 -415);
FORCEPROP 1 LAST PATH I190
J 0
(2700 -150);
DISPLAY 0.978723 (2700 -150);
PAINT WHITE (2700 -150);
DISPLAY INVISIBLE (2700 -150);
FORCEPROP 2 LAST CDS_LIB pure_quanta
J 0
(2650 -325);
PAINT MONO (2650 -325);
DISPLAY INVISIBLE (2650 -325);
FORCEPROP 2 LAST CDS_LOCATION R3317
J 0
(2700 -100);
DISPLAY 1.021277 (2700 -100);
DISPLAY INVISIBLE (2700 -100);
FORCEPROP 2 LAST $SEC 1
J 0
(2700 -100);
DISPLAY 0.680851 (2700 -100);
PAINT MONO (2700 -100);
DISPLAY INVISIBLE (2700 -100);
FORCEPROP 2 LAST CDS_SEC 1
J 0
(2700 -100);
DISPLAY 1.021277 (2700 -100);
DISPLAY INVISIBLE (2700 -100);
FORCEADD Q_RES..2
(2650 -800);
FORCEPROP 1 LAST PART_NUMBER CS31002FB08
J 0
(2690 -925);
DISPLAY 0.510638 (2690 -925);
DISPLAY INVISIBLE (2690 -925);
FORCEPROP 1 LAST WATTAGE 1/16W
J 0
(2690 -825);
DISPLAY 0.510638 (2690 -825);
FORCEPROP 1 LAST MATERIAL CHIP
J 0
(2690 -875);
DISPLAY 0.510638 (2690 -875);
FORCEPROP 1 LAST TOLERANCE 1%
J 0
(2695 -775);
DISPLAY 0.510638 (2695 -775);
FORCEPROP 1 LAST PACK_TYPE 0402LF
J 0
(2690 -975);
DISPLAY 0.510638 (2690 -975);
FORCEPROP 1 LAST VALUE 10K
J 0
(2695 -725);
DISPLAY 0.510638 (2695 -725);
FORCEPROP 1 LAST $LOCATION R3509
J 0
(2695 -675);
DISPLAY 0.978723 (2695 -675);
FORCEPROP 1 LASTPIN (2650 -700) $PN 1
J 0
(2655 -738);
DISPLAY 0.787234 (2655 -738);
PAINT MONO (2655 -738);
FORCEPROP 1 LASTPIN (2650 -900) $PN 2
J 0
(2655 -890);
DISPLAY 0.787234 (2655 -890);
PAINT MONO (2655 -890);
FORCEPROP 1 LAST PATH I191
J 0
(2700 -625);
DISPLAY 0.978723 (2700 -625);
PAINT WHITE (2700 -625);
DISPLAY INVISIBLE (2700 -625);
FORCEPROP 2 LAST CDS_LIB pure_quanta
J 0
(2650 -800);
DISPLAY INVISIBLE (2650 -800);
FORCEPROP 0 LAST CDS_LOCATION R3509
J 0
(2700 -625);
DISPLAY 1.021277 (2700 -625);
DISPLAY INVISIBLE (2700 -625);
FORCEPROP 0 LAST $SEC 1
J 0
(2700 -625);
DISPLAY 0.680851 (2700 -625);
PAINT MONO (2700 -625);
DISPLAY INVISIBLE (2700 -625);
FORCEPROP 0 LAST CDS_SEC 1
J 0
(2700 -625);
DISPLAY 1.021277 (2700 -625);
DISPLAY INVISIBLE (2700 -625);
FORCEADD Q_RES..2
(25 -725);
FORCEPROP 1 LAST PART_NUMBER CS31002FB08
J 0
(65 -850);
DISPLAY 0.510638 (65 -850);
DISPLAY INVISIBLE (65 -850);
FORCEPROP 1 LAST VALUE 10K
J 0
(70 -650);
DISPLAY 0.510638 (70 -650);
FORCEPROP 1 LAST WATTAGE 1/16W
J 0
(65 -750);
DISPLAY 0.510638 (65 -750);
FORCEPROP 1 LAST TOLERANCE 1%
J 0
(70 -700);
DISPLAY 0.510638 (70 -700);
FORCEPROP 1 LAST MATERIAL CHIP
J 0
(65 -800);
DISPLAY 0.510638 (65 -800);
FORCEPROP 1 LAST PACK_TYPE 0402LF
J 0
(65 -900);
DISPLAY 0.510638 (65 -900);
FORCEPROP 1 LAST $LOCATION R3507
J 0
(70 -600);
DISPLAY 0.978723 (70 -600);
FORCEPROP 1 LASTPIN (25 -625) $PN 1
J 0
(30 -663);
DISPLAY 0.787234 (30 -663);
PAINT MONO (30 -663);
FORCEPROP 1 LASTPIN (25 -825) $PN 2
J 0
(30 -815);
DISPLAY 0.787234 (30 -815);
PAINT MONO (30 -815);
FORCEPROP 1 LAST PATH I192
J 0
(75 -550);
DISPLAY 0.978723 (75 -550);
PAINT WHITE (75 -550);
DISPLAY INVISIBLE (75 -550);
FORCEPROP 2 LAST CDS_LIB pure_quanta
J 0
(25 -725);
DISPLAY INVISIBLE (25 -725);
FORCEPROP 0 LAST CDS_LOCATION R3507
J 0
(75 -550);
DISPLAY 1.021277 (75 -550);
DISPLAY INVISIBLE (75 -550);
FORCEPROP 0 LAST $SEC 1
J 0
(75 -550);
DISPLAY 0.680851 (75 -550);
PAINT MONO (75 -550);
DISPLAY INVISIBLE (75 -550);
FORCEPROP 0 LAST CDS_SEC 1
J 0
(75 -550);
DISPLAY 1.021277 (75 -550);
DISPLAY INVISIBLE (75 -550);
FORCEADD Q_RES..2
(0 -250);
FORCEPROP 1 LAST PART_NUMBER CS24702JB10
J 0
(40 -425);
DISPLAY 0.638298 (40 -425);
DISPLAY INVISIBLE (40 -425);
FORCEPROP 1 LAST VALUE 4.7K
J 0
(45 -175);
DISPLAY 0.638298 (45 -175);
FORCEPROP 1 LAST TOLERANCE 5%
J 0
(45 -225);
DISPLAY 0.638298 (45 -225);
FORCEPROP 1 LAST WATTAGE 1/16W
J 0
(40 -275);
DISPLAY 0.638298 (40 -275);
FORCEPROP 1 LAST MATERIAL EMPTY
J 0
(40 -325);
DISPLAY 0.638298 (40 -325);
PAINT RED (40 -325);
FORCEPROP 1 LAST PACK_TYPE 0402LF
J 0
(40 -375);
DISPLAY 0.638298 (40 -375);
FORCEPROP 1 LAST $LOCATION R3506
J 0
(45 -125);
DISPLAY 0.978723 (45 -125);
FORCEPROP 1 LASTPIN (0 -150) $PN 1
J 0
(5 -188);
DISPLAY 0.787234 (5 -188);
PAINT MONO (5 -188);
FORCEPROP 1 LASTPIN (0 -350) $PN 2
J 0
(5 -340);
DISPLAY 0.787234 (5 -340);
PAINT MONO (5 -340);
FORCEPROP 2 LAST CDS_LIB pure_quanta
J 0
(0 -250);
DISPLAY INVISIBLE (0 -250);
FORCEPROP 1 LAST PATH I193
J 0
(50 -75);
DISPLAY 0.978723 (50 -75);
PAINT WHITE (50 -75);
DISPLAY INVISIBLE (50 -75);
FORCEPROP 0 LAST CDS_LOCATION R3506
J 0
(50 -75);
DISPLAY 1.021277 (50 -75);
DISPLAY INVISIBLE (50 -75);
FORCEPROP 0 LAST $SEC 1
J 0
(50 -75);
DISPLAY 0.680851 (50 -75);
PAINT MONO (50 -75);
DISPLAY INVISIBLE (50 -75);
FORCEPROP 0 LAST CDS_SEC 1
J 0
(50 -75);
DISPLAY 1.021277 (50 -75);
DISPLAY INVISIBLE (50 -75);
FORCEADD Q_RES..2
(2625 325);
FORCEPROP 1 LAST PART_NUMBER CS35492FB03
J 0
(2665 200);
DISPLAY 0.787234 (2665 200);
DISPLAY INVISIBLE (2665 200);
FORCEPROP 1 LAST PACK_TYPE 0402LF
J 0
(2665 150);
DISPLAY 0.787234 (2665 150);
FORCEPROP 1 LAST TOLERANCE 1%
J 0
(2670 350);
DISPLAY 0.787234 (2670 350);
FORCEPROP 1 LAST VALUE 54.9K
J 0
(2670 400);
DISPLAY 0.787234 (2670 400);
FORCEPROP 1 LAST WATTAGE 1/16W
J 0
(2665 300);
DISPLAY 0.787234 (2665 300);
FORCEPROP 1 LAST MATERIAL CHIP
J 0
(2665 250);
DISPLAY 0.787234 (2665 250);
FORCEPROP 1 LAST $LOCATION R3508
J 0
(2670 450);
DISPLAY 0.978723 (2670 450);
FORCEPROP 1 LASTPIN (2625 425) $PN 1
J 0
(2630 387);
DISPLAY 0.787234 (2630 387);
PAINT MONO (2630 387);
FORCEPROP 1 LASTPIN (2625 225) $PN 2
J 0
(2630 235);
DISPLAY 0.787234 (2630 235);
PAINT MONO (2630 235);
FORCEPROP 1 LAST PATH I194
J 0
(2675 500);
DISPLAY 0.978723 (2675 500);
PAINT WHITE (2675 500);
DISPLAY INVISIBLE (2675 500);
FORCEPROP 2 LAST CDS_LIB pure_quanta
J 0
(2625 325);
DISPLAY INVISIBLE (2625 325);
FORCEPROP 0 LAST CDS_LOCATION R3508
J 0
(2675 500);
DISPLAY 1.021277 (2675 500);
DISPLAY INVISIBLE (2675 500);
FORCEPROP 0 LAST $SEC 1
J 0
(2675 500);
DISPLAY 0.680851 (2675 500);
PAINT MONO (2675 500);
DISPLAY INVISIBLE (2675 500);
FORCEPROP 0 LAST CDS_SEC 1
J 0
(2675 500);
DISPLAY 1.021277 (2675 500);
DISPLAY INVISIBLE (2675 500);
FORCEADD 74LVC1G126SE7..1
(-550 -1900);
FORCEPROP 1 LAST PART_NUMBER AL1G0126009
J 0
(-469 -2191);
DISPLAY 0.723404 (-469 -2191);
PAINT GREEN (-469 -2191);
DISPLAY INVISIBLE (-469 -2191);
FORCEPROP 2 LAST PART_TYPE SMLF
J 0
(-425 -1725);
DISPLAY 0.638298 (-425 -1725);
FORCEPROP 1 LAST MATERIAL IC
J 0
(-475 -2250);
DISPLAY 0.723404 (-475 -2250);
PAINT GREEN (-475 -2250);
FORCEPROP 2 LAST VALUE 74LVC1G126SE-7
J 0
(-525 -1750);
DISPLAY 0.638298 (-525 -1750);
FORCEPROP 1 LAST LOCATION U204
J 0
(-444 -2069);
DISPLAY 0.723404 (-444 -2069);
PAINT GREEN (-444 -2069);
FORCEPROP 0 LASTPIN (-800 -1850) $PN 2
J 2
(-810 -1840);
DISPLAY 0.680851 (-810 -1840);
PAINT MONO (-810 -1840);
FORCEPROP 0 LASTPIN (-550 -2150) $PN 3
R 1
J 2
(-560 -2160);
DISPLAY 0.680851 (-560 -2160);
PAINT MONO (-560 -2160);
FORCEPROP 0 LASTPIN (-800 -1950) $PN 1
J 2
(-810 -1940);
DISPLAY 0.680851 (-810 -1940);
PAINT MONO (-810 -1940);
FORCEPROP 0 LASTPIN (-550 -1650) $PN 5
R 1
J 0
(-560 -1640);
DISPLAY 0.680851 (-560 -1640);
PAINT MONO (-560 -1640);
FORCEPROP 0 LASTPIN (-300 -1900) $PN 4
J 0
(-290 -1890);
DISPLAY 0.680851 (-290 -1890);
PAINT MONO (-290 -1890);
FORCEPROP 2 LAST CDS_LIB pure_quanta
J 0
(-550 -1900);
DISPLAY INVISIBLE (-550 -1900);
FORCEPROP 1 LAST CDS_LMAN_SYM_OUTLINE -100,100,100,-100
J 0
(-550 -1900);
DISPLAY 0.468085 (-550 -1900);
PAINT GREEN (-550 -1900);
DISPLAY INVISIBLE (-550 -1900);
FORCEPROP 1 LAST PATH I195
J 0
(-550 -1900);
DISPLAY 0.723404 (-550 -1900);
PAINT GREEN (-550 -1900);
DISPLAY INVISIBLE (-550 -1900);
FORCEPROP 1 LAST NEEDS_NO_SIZE TRUE
J 0
(-550 -1900);
DISPLAY 0.723404 (-550 -1900);
PAINT GREEN (-550 -1900);
DISPLAY INVISIBLE (-550 -1900);
FORCEPROP 0 LAST $SEC 1
J 0
(-425 -1675);
DISPLAY 0.680851 (-425 -1675);
PAINT MONO (-425 -1675);
DISPLAY INVISIBLE (-425 -1675);
FORCEPROP 0 LAST CDS_SEC 1
J 0
(-425 -1675);
DISPLAY 1.021277 (-425 -1675);
DISPLAY INVISIBLE (-425 -1675);
FORCEADD UNIVERSAL_GND..1
(-550 -2300);
FORCEPROP 3 LASTPIN (-550 -2250) SIG_NAME GND\g
J 0
(-540 -2240);
DISPLAY 0.659574 (-540 -2240);
PAINT MONO (-540 -2240);
DISPLAY INVISIBLE (-540 -2240);
FORCEPROP 2 LAST CDS_LIB logical_power
J 0
(-550 -2300);
DISPLAY INVISIBLE (-550 -2300);
FORCEPROP 1 LAST PATH I196
J 0
(-475 -2300);
DISPLAY 0.872340 (-475 -2300);
PAINT AQUA (-475 -2300);
DISPLAY INVISIBLE (-475 -2300);
FORCEPROP 1 LAST HDL_POWER GND
J 1
(-525 -2375);
DISPLAY 0.872340 (-525 -2375);
PAINT GREEN (-525 -2375);
DISPLAY INVISIBLE (-525 -2375);
FORCEADD Q_RES..1
(650 -1900);
FORCEPROP 1 LAST PART_NUMBER CS03322FB03
J 0
(250 -2000);
DISPLAY 0.723404 (250 -2000);
PAINT WHITE (250 -2000);
DISPLAY INVISIBLE (250 -2000);
FORCEPROP 1 LAST PACK_TYPE 0402LF
J 0
(475 -1950);
DISPLAY 0.723404 (475 -1950);
FORCEPROP 1 LAST MATERIAL CHIP
J 0
(675 -1950);
DISPLAY 0.723404 (675 -1950);
FORCEPROP 1 LAST VALUE 33.2
J 2
(900 -1900);
DISPLAY 0.723404 (900 -1900);
FORCEPROP 1 LAST LOCATION R3036
J 0
(450 -1900);
DISPLAY 0.638298 (450 -1900);
FORCEPROP 1 LASTPIN (550 -1900) $PN 1
J 0
(562 -1888);
DISPLAY 0.787234 (562 -1888);
PAINT MONO (562 -1888);
FORCEPROP 1 LASTPIN (750 -1900) $PN 2
J 0
(712 -1888);
DISPLAY 0.787234 (712 -1888);
PAINT MONO (712 -1888);
FORCEPROP 2 LAST CDS_LIB pure_quanta
J 0
(650 -1900);
DISPLAY INVISIBLE (650 -1900);
FORCEPROP 1 LAST PATH I197
J 0
(600 -1750);
DISPLAY 0.978723 (600 -1750);
PAINT WHITE (600 -1750);
DISPLAY INVISIBLE (600 -1750);
FORCEPROP 1 LAST WATTAGE 1/16W
J 2
(1050 -1950);
DISPLAY 0.723404 (1050 -1950);
PAINT SKYBLUE (1050 -1950);
DISPLAY INVISIBLE (1050 -1950);
FORCEPROP 1 LAST TOLERANCE 1%
J 0
(1125 -1900);
DISPLAY 0.723404 (1125 -1900);
PAINT SKYBLUE (1125 -1900);
DISPLAY INVISIBLE (1125 -1900);
FORCEPROP 0 LAST $SEC 1
J 0
(900 -1850);
DISPLAY 0.680851 (900 -1850);
PAINT MONO (900 -1850);
DISPLAY INVISIBLE (900 -1850);
FORCEPROP 0 LAST CDS_SEC 1
J 0
(900 -1850);
DISPLAY 1.021277 (900 -1850);
DISPLAY INVISIBLE (900 -1850);
FORCEADD Q_RES..2
(0 2150);
FORCEPROP 1 LAST PART_NUMBER CS24702JB10
J 0
(40 1975);
DISPLAY 0.638298 (40 1975);
DISPLAY INVISIBLE (40 1975);
FORCEPROP 1 LAST VALUE 4.7K
J 0
(45 2225);
DISPLAY 0.638298 (45 2225);
FORCEPROP 1 LAST TOLERANCE 5%
J 0
(45 2175);
DISPLAY 0.638298 (45 2175);
FORCEPROP 1 LAST WATTAGE 1/16W
J 0
(40 2125);
DISPLAY 0.638298 (40 2125);
FORCEPROP 1 LAST MATERIAL CHIP
J 0
(40 2075);
DISPLAY 0.638298 (40 2075);
FORCEPROP 1 LAST PACK_TYPE 0402LF
J 0
(40 2025);
DISPLAY 0.638298 (40 2025);
FORCEPROP 1 LAST LOCATION R2909
J 0
(45 2275);
DISPLAY 0.978723 (45 2275);
FORCEPROP 1 LASTPIN (0 2250) $PN 1
J 0
(5 2212);
DISPLAY 0.787234 (5 2212);
PAINT MONO (5 2212);
FORCEPROP 1 LASTPIN (0 2050) $PN 2
J 0
(5 2060);
DISPLAY 0.787234 (5 2060);
PAINT MONO (5 2060);
FORCEPROP 2 LAST CDS_LIB pure_quanta
J 0
(0 2150);
DISPLAY INVISIBLE (0 2150);
FORCEPROP 1 LAST PATH I198
J 0
(50 2325);
DISPLAY 0.978723 (50 2325);
PAINT WHITE (50 2325);
DISPLAY INVISIBLE (50 2325);
FORCEPROP 0 LAST $SEC 1
J 0
(50 2325);
DISPLAY 0.680851 (50 2325);
PAINT MONO (50 2325);
DISPLAY INVISIBLE (50 2325);
FORCEPROP 0 LAST CDS_SEC 1
J 0
(50 2325);
DISPLAY 1.021277 (50 2325);
DISPLAY INVISIBLE (50 2325);
FORCEADD UNIVERSAL_POWER..1
(-1900 -1200);
FORCEPROP 3 LASTPIN (-1900 -1250) SIG_NAME P3V3_AUX\g
J 0
(-1890 -1240);
DISPLAY 0.659574 (-1890 -1240);
PAINT MONO (-1890 -1240);
DISPLAY INVISIBLE (-1890 -1240);
FORCEPROP 1 LAST HDL_POWER P3V3_AUX
J 1
(-1900 -1150);
DISPLAY 0.872340 (-1900 -1150);
PAINT GREEN (-1900 -1150);
FORCEPROP 1 LAST PATH I199
J 0
(-1850 -1175);
DISPLAY 0.872340 (-1850 -1175);
PAINT AQUA (-1850 -1175);
DISPLAY INVISIBLE (-1850 -1175);
FORCEPROP 2 LAST CDS_LIB logical_power
J 0
(-1900 -1200);
DISPLAY INVISIBLE (-1900 -1200);
FORCEADD Q_RES..2
(-1900 -1525);
FORCEPROP 1 LAST PART_NUMBER CS41002FB09
J 0
(-1860 -1650);
DISPLAY 0.510638 (-1860 -1650);
DISPLAY INVISIBLE (-1860 -1650);
FORCEPROP 1 LAST MATERIAL CHIP
J 0
(-1860 -1600);
DISPLAY 0.510638 (-1860 -1600);
FORCEPROP 1 LAST PACK_TYPE 0402LF
J 0
(-1860 -1700);
DISPLAY 0.510638 (-1860 -1700);
FORCEPROP 1 LAST TOLERANCE 1%
J 0
(-1855 -1500);
DISPLAY 0.510638 (-1855 -1500);
FORCEPROP 1 LAST WATTAGE 1/16W
J 0
(-1860 -1550);
DISPLAY 0.510638 (-1860 -1550);
FORCEPROP 1 LAST VALUE 100K
J 0
(-1855 -1450);
DISPLAY 0.510638 (-1855 -1450);
FORCEPROP 1 LAST LOCATION R4515
J 0
(-1855 -1400);
DISPLAY 0.787234 (-1855 -1400);
FORCEPROP 1 LASTPIN (-1900 -1425) $PN 1
J 0
(-1895 -1463);
DISPLAY 0.787234 (-1895 -1463);
PAINT MONO (-1895 -1463);
FORCEPROP 1 LASTPIN (-1900 -1625) $PN 2
J 0
(-1895 -1615);
DISPLAY 0.787234 (-1895 -1615);
PAINT MONO (-1895 -1615);
FORCEPROP 1 LAST PATH I200
J 0
(-1850 -1350);
DISPLAY 0.978723 (-1850 -1350);
PAINT WHITE (-1850 -1350);
DISPLAY INVISIBLE (-1850 -1350);
FORCEPROP 2 LAST CDS_LIB pure_quanta
J 0
(-1900 -1525);
DISPLAY INVISIBLE (-1900 -1525);
FORCEPROP 0 LAST $SEC 1
J 0
(-1850 -1350);
DISPLAY 0.680851 (-1850 -1350);
PAINT MONO (-1850 -1350);
DISPLAY INVISIBLE (-1850 -1350);
FORCEPROP 0 LAST CDS_SEC 1
J 0
(-1850 -1350);
DISPLAY 1.021277 (-1850 -1350);
DISPLAY INVISIBLE (-1850 -1350);
FORCEADD UNIVERSAL_POWER..1
(400 -1250);
FORCEPROP 3 LASTPIN (400 -1300) SIG_NAME P3V3_AUX\g
J 0
(410 -1290);
DISPLAY 0.659574 (410 -1290);
PAINT MONO (410 -1290);
DISPLAY INVISIBLE (410 -1290);
FORCEPROP 1 LAST HDL_POWER P3V3_AUX
J 1
(400 -1200);
DISPLAY 0.872340 (400 -1200);
PAINT GREEN (400 -1200);
FORCEPROP 2 LAST CDS_LIB logical_power
J 0
(400 -1250);
DISPLAY INVISIBLE (400 -1250);
FORCEPROP 1 LAST PATH I201
J 0
(450 -1225);
DISPLAY 0.872340 (450 -1225);
PAINT AQUA (450 -1225);
DISPLAY INVISIBLE (450 -1225);
FORCEADD Q_RES..2
(400 -1575);
FORCEPROP 1 LAST PART_NUMBER CS41002FB09
J 0
(440 -1700);
DISPLAY 0.510638 (440 -1700);
DISPLAY INVISIBLE (440 -1700);
FORCEPROP 1 LAST PACK_TYPE 0402LF
J 0
(440 -1750);
DISPLAY 0.510638 (440 -1750);
FORCEPROP 1 LAST TOLERANCE 1%
J 0
(445 -1550);
DISPLAY 0.510638 (445 -1550);
FORCEPROP 1 LAST VALUE 100K
J 0
(445 -1500);
DISPLAY 0.510638 (445 -1500);
FORCEPROP 1 LAST MATERIAL EMPTY
J 0
(440 -1650);
DISPLAY 0.510638 (440 -1650);
PAINT RED (440 -1650);
FORCEPROP 1 LAST WATTAGE 1/16W
J 0
(440 -1600);
DISPLAY 0.510638 (440 -1600);
FORCEPROP 1 LAST LOCATION R4173
J 0
(445 -1450);
DISPLAY 0.978723 (445 -1450);
FORCEPROP 1 LASTPIN (400 -1475) $PN 1
J 0
(405 -1513);
DISPLAY 0.787234 (405 -1513);
PAINT MONO (405 -1513);
FORCEPROP 1 LASTPIN (400 -1675) $PN 2
J 0
(405 -1665);
DISPLAY 0.787234 (405 -1665);
PAINT MONO (405 -1665);
FORCEPROP 2 LAST CDS_LIB pure_quanta
J 0
(400 -1575);
DISPLAY INVISIBLE (400 -1575);
FORCEPROP 1 LAST PATH I202
J 0
(450 -1400);
DISPLAY 0.978723 (450 -1400);
PAINT WHITE (450 -1400);
DISPLAY INVISIBLE (450 -1400);
FORCEPROP 0 LAST $SEC 1
J 0
(450 -1400);
DISPLAY 0.680851 (450 -1400);
PAINT MONO (450 -1400);
DISPLAY INVISIBLE (450 -1400);
FORCEPROP 0 LAST CDS_SEC 1
J 0
(450 -1400);
DISPLAY 1.021277 (450 -1400);
DISPLAY INVISIBLE (450 -1400);
FORCEADD Q_RES..2
(2625 1575);
FORCEPROP 1 LAST PART_NUMBER CS41002FB09
J 0
(2665 1450);
DISPLAY 0.510638 (2665 1450);
DISPLAY INVISIBLE (2665 1450);
FORCEPROP 1 LAST TOLERANCE 1%
J 0
(2670 1600);
DISPLAY 0.510638 (2670 1600);
FORCEPROP 1 LAST VALUE 100K
J 0
(2670 1650);
DISPLAY 0.510638 (2670 1650);
FORCEPROP 1 LAST PACK_TYPE 0402LF
J 0
(2665 1400);
DISPLAY 0.510638 (2665 1400);
FORCEPROP 1 LAST WATTAGE 1/16W
J 0
(2665 1550);
DISPLAY 0.510638 (2665 1550);
FORCEPROP 1 LAST MATERIAL CHIP
J 0
(2665 1500);
DISPLAY 0.510638 (2665 1500);
FORCEPROP 1 LAST LOCATION R2927
J 0
(2670 1700);
DISPLAY 0.978723 (2670 1700);
FORCEPROP 1 LASTPIN (2625 1675) $PN 1
J 0
(2630 1637);
DISPLAY 0.787234 (2630 1637);
PAINT MONO (2630 1637);
FORCEPROP 1 LASTPIN (2625 1475) $PN 2
J 0
(2630 1485);
DISPLAY 0.787234 (2630 1485);
PAINT MONO (2630 1485);
FORCEPROP 1 LAST PATH I203
J 0
(2675 1750);
DISPLAY 0.978723 (2675 1750);
PAINT WHITE (2675 1750);
DISPLAY INVISIBLE (2675 1750);
FORCEPROP 2 LAST CDS_LIB pure_quanta
J 0
(2625 1575);
DISPLAY INVISIBLE (2625 1575);
FORCEPROP 0 LAST $SEC 1
J 0
(2675 1750);
DISPLAY 0.680851 (2675 1750);
PAINT MONO (2675 1750);
DISPLAY INVISIBLE (2675 1750);
FORCEPROP 0 LAST CDS_SEC 1
J 0
(2675 1750);
DISPLAY 1.021277 (2675 1750);
DISPLAY INVISIBLE (2675 1750);
FORCEADD Q_RES..1
(2825 600);
FORCEPROP 1 LAST PART_NUMBER CS04992FB07
J 0
(2925 575);
DISPLAY 0.404255 (2925 575);
DISPLAY INVISIBLE (2925 575);
FORCEPROP 1 LAST VALUE 49.9
J 2
(3050 600);
DISPLAY 0.510638 (3050 600);
FORCEPROP 1 LAST MATERIAL CHIP
J 0
(2675 575);
DISPLAY 0.404255 (2675 575);
FORCEPROP 1 LAST LOCATION R2925
J 0
(2600 600);
DISPLAY 0.638298 (2600 600);
FORCEPROP 1 LASTPIN (2725 600) $PN 1
J 0
(2737 612);
DISPLAY 0.787234 (2737 612);
PAINT MONO (2737 612);
FORCEPROP 1 LASTPIN (2925 600) $PN 2
J 0
(2887 612);
DISPLAY 0.787234 (2887 612);
PAINT MONO (2887 612);
FORCEPROP 1 LAST PACK_TYPE 0402LF
J 0
(3125 600);
DISPLAY 0.510638 (3125 600);
DISPLAY INVISIBLE (3125 600);
FORCEPROP 1 LAST TOLERANCE 1%
J 0
(3050 600);
DISPLAY 0.510638 (3050 600);
DISPLAY INVISIBLE (3050 600);
FORCEPROP 1 LAST WATTAGE 1/16W
J 2
(3125 550);
DISPLAY 0.404255 (3125 550);
DISPLAY INVISIBLE (3125 550);
FORCEPROP 2 LAST CDS_LIB pure_quanta
J 0
(2825 600);
DISPLAY INVISIBLE (2825 600);
FORCEPROP 1 LAST PATH I204
J 0
(2775 750);
DISPLAY 0.978723 (2775 750);
PAINT WHITE (2775 750);
DISPLAY INVISIBLE (2775 750);
FORCEPROP 0 LAST $SEC 1
J 0
(2600 650);
DISPLAY 0.680851 (2600 650);
PAINT MONO (2600 650);
DISPLAY INVISIBLE (2600 650);
FORCEPROP 0 LAST CDS_SEC 1
J 0
(2600 650);
DISPLAY 1.021277 (2600 650);
DISPLAY INVISIBLE (2600 650);
FORCEADD Q_RES..1
(2900 -525);
FORCEPROP 1 LAST PART_NUMBER CS04992FB07
J 0
(3000 -550);
DISPLAY 0.404255 (3000 -550);
DISPLAY INVISIBLE (3000 -550);
FORCEPROP 1 LAST VALUE 49.9
J 2
(3125 -525);
DISPLAY 0.510638 (3125 -525);
FORCEPROP 1 LAST MATERIAL CHIP
J 0
(2750 -550);
DISPLAY 0.404255 (2750 -550);
FORCEPROP 1 LAST LOCATION R3315
J 0
(2675 -525);
DISPLAY 0.638298 (2675 -525);
FORCEPROP 1 LASTPIN (2800 -525) $PN 1
J 0
(2812 -513);
DISPLAY 0.787234 (2812 -513);
PAINT MONO (2812 -513);
FORCEPROP 1 LASTPIN (3000 -525) $PN 2
J 0
(2962 -513);
DISPLAY 0.787234 (2962 -513);
PAINT MONO (2962 -513);
FORCEPROP 1 LAST PACK_TYPE 0402LF
J 0
(3200 -525);
DISPLAY 0.510638 (3200 -525);
DISPLAY INVISIBLE (3200 -525);
FORCEPROP 1 LAST TOLERANCE 1%
J 0
(3125 -525);
DISPLAY 0.510638 (3125 -525);
DISPLAY INVISIBLE (3125 -525);
FORCEPROP 1 LAST WATTAGE 1/16W
J 2
(3200 -575);
DISPLAY 0.404255 (3200 -575);
DISPLAY INVISIBLE (3200 -575);
FORCEPROP 2 LAST CDS_LIB pure_quanta
J 0
(2900 -525);
DISPLAY INVISIBLE (2900 -525);
FORCEPROP 1 LAST PATH I205
J 0
(2850 -375);
DISPLAY 0.978723 (2850 -375);
PAINT WHITE (2850 -375);
DISPLAY INVISIBLE (2850 -375);
FORCEPROP 0 LAST $SEC 1
J 0
(2675 -475);
DISPLAY 0.680851 (2675 -475);
PAINT MONO (2675 -475);
DISPLAY INVISIBLE (2675 -475);
FORCEPROP 0 LAST CDS_SEC 1
J 0
(2675 -475);
DISPLAY 1.021277 (2675 -475);
DISPLAY INVISIBLE (2675 -475);
FORCEADD Q_RES..1
(2850 3000);
FORCEPROP 1 LAST PART_NUMBER CS04992FB07
J 0
(2950 2975);
DISPLAY 0.404255 (2950 2975);
DISPLAY INVISIBLE (2950 2975);
FORCEPROP 1 LAST VALUE 49.9
J 2
(3075 3000);
DISPLAY 0.510638 (3075 3000);
FORCEPROP 1 LAST MATERIAL CHIP
J 0
(2700 2975);
DISPLAY 0.404255 (2700 2975);
FORCEPROP 1 LAST LOCATION R2917
J 0
(2625 3000);
DISPLAY 0.638298 (2625 3000);
FORCEPROP 1 LASTPIN (2750 3000) $PN 1
J 0
(2762 3012);
DISPLAY 0.787234 (2762 3012);
PAINT MONO (2762 3012);
FORCEPROP 1 LASTPIN (2950 3000) $PN 2
J 0
(2912 3012);
DISPLAY 0.787234 (2912 3012);
PAINT MONO (2912 3012);
FORCEPROP 1 LAST PACK_TYPE 0402LF
J 0
(3150 3000);
DISPLAY 0.510638 (3150 3000);
DISPLAY INVISIBLE (3150 3000);
FORCEPROP 1 LAST TOLERANCE 1%
J 0
(3075 3000);
DISPLAY 0.510638 (3075 3000);
DISPLAY INVISIBLE (3075 3000);
FORCEPROP 1 LAST WATTAGE 1/16W
J 2
(3150 2950);
DISPLAY 0.404255 (3150 2950);
DISPLAY INVISIBLE (3150 2950);
FORCEPROP 1 LAST PATH I206
J 0
(2800 3150);
DISPLAY 0.978723 (2800 3150);
PAINT WHITE (2800 3150);
DISPLAY INVISIBLE (2800 3150);
FORCEPROP 2 LAST CDS_LIB pure_quanta
J 0
(2850 3000);
DISPLAY INVISIBLE (2850 3000);
FORCEPROP 0 LAST $SEC 1
J 0
(2625 3050);
DISPLAY 0.680851 (2625 3050);
PAINT MONO (2625 3050);
DISPLAY INVISIBLE (2625 3050);
FORCEPROP 0 LAST CDS_SEC 1
J 0
(2625 3050);
DISPLAY 1.021277 (2625 3050);
DISPLAY INVISIBLE (2625 3050);
FORCEADD Q_RES..1
(2925 1875);
FORCEPROP 1 LAST PART_NUMBER CS04992FB07
J 0
(3025 1850);
DISPLAY 0.404255 (3025 1850);
DISPLAY INVISIBLE (3025 1850);
FORCEPROP 1 LAST MATERIAL CHIP
J 0
(2775 1850);
DISPLAY 0.404255 (2775 1850);
FORCEPROP 1 LAST VALUE 49.9
J 2
(3150 1875);
DISPLAY 0.510638 (3150 1875);
FORCEPROP 1 LAST LOCATION R2924
J 0
(2700 1875);
DISPLAY 0.638298 (2700 1875);
FORCEPROP 1 LASTPIN (2825 1875) $PN 1
J 0
(2837 1887);
DISPLAY 0.787234 (2837 1887);
PAINT MONO (2837 1887);
FORCEPROP 1 LASTPIN (3025 1875) $PN 2
J 0
(2987 1887);
DISPLAY 0.787234 (2987 1887);
PAINT MONO (2987 1887);
FORCEPROP 2 LAST CDS_LIB pure_quanta
J 0
(2925 1875);
DISPLAY INVISIBLE (2925 1875);
FORCEPROP 1 LAST PATH I207
J 0
(2875 2025);
DISPLAY 0.978723 (2875 2025);
PAINT WHITE (2875 2025);
DISPLAY INVISIBLE (2875 2025);
FORCEPROP 1 LAST WATTAGE 1/16W
J 2
(3225 1825);
DISPLAY 0.404255 (3225 1825);
DISPLAY INVISIBLE (3225 1825);
FORCEPROP 1 LAST TOLERANCE 1%
J 0
(3150 1875);
DISPLAY 0.510638 (3150 1875);
DISPLAY INVISIBLE (3150 1875);
FORCEPROP 1 LAST PACK_TYPE 0402LF
J 0
(3225 1875);
DISPLAY 0.510638 (3225 1875);
DISPLAY INVISIBLE (3225 1875);
FORCEPROP 0 LAST $SEC 1
J 0
(2700 1925);
DISPLAY 0.680851 (2700 1925);
PAINT MONO (2700 1925);
DISPLAY INVISIBLE (2700 1925);
FORCEPROP 0 LAST CDS_SEC 1
J 0
(2700 1925);
DISPLAY 1.021277 (2700 1925);
DISPLAY INVISIBLE (2700 1925);
FORCEADD Q_RES..1
(-1575 -1950);
FORCEPROP 1 LAST PART_NUMBER CS03322FB03
J 0
(-1700 -1900);
DISPLAY 0.638298 (-1700 -1900);
DISPLAY INVISIBLE (-1700 -1900);
FORCEPROP 1 LAST TOLERANCE 1%
J 0
(-1375 -1975);
DISPLAY 0.510638 (-1375 -1975);
FORCEPROP 1 LAST VALUE 33.2
J 2
(-1400 -1975);
DISPLAY 0.510638 (-1400 -1975);
FORCEPROP 1 LAST PACK_TYPE 0402LF
J 0
(-1275 -1975);
DISPLAY 0.510638 (-1275 -1975);
FORCEPROP 1 LAST MATERIAL CHIP
J 0
(-1500 -1950);
DISPLAY 0.638298 (-1500 -1950);
FORCEPROP 1 LAST LOCATION R3063
J 0
(-1825 -1950);
DISPLAY 0.638298 (-1825 -1950);
FORCEPROP 1 LASTPIN (-1675 -1950) $PN 1
J 0
(-1663 -1938);
DISPLAY 0.787234 (-1663 -1938);
PAINT MONO (-1663 -1938);
FORCEPROP 1 LASTPIN (-1475 -1950) $PN 2
J 0
(-1513 -1938);
DISPLAY 0.787234 (-1513 -1938);
PAINT MONO (-1513 -1938);
FORCEPROP 2 LAST CDS_LIB pure_quanta
J 0
(-1575 -1950);
DISPLAY INVISIBLE (-1575 -1950);
FORCEPROP 1 LAST PATH I208
J 0
(-1625 -1800);
DISPLAY 0.978723 (-1625 -1800);
PAINT WHITE (-1625 -1800);
DISPLAY INVISIBLE (-1625 -1800);
FORCEPROP 1 LAST WATTAGE 1/16W
J 2
(-1375 -1850);
DISPLAY 0.638298 (-1375 -1850);
DISPLAY INVISIBLE (-1375 -1850);
FORCEPROP 0 LAST $SEC 1
J 0
(-1500 -1900);
DISPLAY 0.680851 (-1500 -1900);
PAINT MONO (-1500 -1900);
DISPLAY INVISIBLE (-1500 -1900);
FORCEPROP 0 LAST CDS_SEC 1
J 0
(-1500 -1900);
DISPLAY 1.021277 (-1500 -1900);
DISPLAY INVISIBLE (-1500 -1900);
FORCEADD OFFPAGE..2
(2125 -1900);
FORCEPROP 2 LAST $XR0 240 
J 0
(2314 -1900);
DISPLAY 0.638298 (2314 -1900);
PAINT MONO (2314 -1900);
FORCEPROP 1 LAST COMMENT_BODY TRUE
J 0
(2080 -1995);
DISPLAY 0.872340 (2080 -1995);
PAINT GREEN (2080 -1995);
DISPLAY INVISIBLE (2080 -1995);
FORCEPROP 1 LAST OFFPAGE TRUE
J 0
(2450 -2025);
DISPLAY 0.872340 (2450 -2025);
PAINT AQUA (2450 -2025);
DISPLAY INVISIBLE (2450 -2025);
FORCEPROP 2 LAST PATH I209
J 0
(2300 -1825);
DISPLAY 1.021277 (2300 -1825);
DISPLAY INVISIBLE (2300 -1825);
FORCEPROP 2 LAST CDS_LIB standard
J 0
(2125 -1900);
DISPLAY INVISIBLE (2125 -1900);
FORCEADD 74LVC2G17GW..1
(1475 2450);
FORCEPROP 1 LAST PART_NUMBER AL2G0017005
J 0
(1275 1675);
DISPLAY 0.723404 (1275 1675);
PAINT GREEN (1275 1675);
DISPLAY INVISIBLE (1275 1675);
FORCEPROP 2 LAST PART_TYPE SMLF
J 0
(1275 1775);
DISPLAY 1.021277 (1275 1775);
FORCEPROP 1 LAST MATERIAL IC
J 0
(1275 1625);
DISPLAY 0.723404 (1275 1625);
PAINT GREEN (1275 1625);
FORCEPROP 2 LAST VALUE 74LVC2G17GW
J 0
(1275 1725);
DISPLAY 1.021277 (1275 1725);
FORCEPROP 1 LAST $LOCATION U195
J 0
(1702 2210);
DISPLAY 0.723404 (1702 2210);
PAINT GREEN (1702 2210);
FORCEPROP 0 LASTPIN (1100 2575) $PN 1
J 2
(1090 2585);
DISPLAY 0.680851 (1090 2585);
PAINT MONO (1090 2585);
FORCEPROP 0 LASTPIN (1100 2325) $PN 3
J 2
(1090 2335);
DISPLAY 0.680851 (1090 2335);
PAINT MONO (1090 2335);
FORCEPROP 0 LASTPIN (1850 2575) $PN 6
J 0
(1860 2585);
DISPLAY 0.680851 (1860 2585);
PAINT MONO (1860 2585);
FORCEPROP 0 LASTPIN (1850 2325) $PN 4
J 0
(1860 2335);
DISPLAY 0.680851 (1860 2335);
PAINT MONO (1860 2335);
FORCEPROP 0 LASTPIN (1500 2025) $PN 2
R 1
J 2
(1490 2015);
DISPLAY 0.680851 (1490 2015);
PAINT MONO (1490 2015);
FORCEPROP 0 LASTPIN (1500 2875) $PN 5
R 1
J 0
(1490 2885);
DISPLAY 0.680851 (1490 2885);
PAINT MONO (1490 2885);
FORCEPROP 1 LAST CDS_LMAN_SYM_OUTLINE -225,275,225,-275
J 0
(1475 2450);
DISPLAY 0.468085 (1475 2450);
PAINT GREEN (1475 2450);
DISPLAY INVISIBLE (1475 2450);
FORCEPROP 1 LAST NEEDS_NO_SIZE TRUE
J 0
(1700 2449);
DISPLAY 0.468085 (1700 2449);
PAINT GREEN (1700 2449);
DISPLAY INVISIBLE (1700 2449);
FORCEPROP 2 LAST CDS_LIB pure_quanta
J 0
(1475 2450);
DISPLAY INVISIBLE (1475 2450);
FORCEPROP 1 LAST PATH I65
J 0
(1700 2175);
DISPLAY 0.723404 (1700 2175);
PAINT GREEN (1700 2175);
DISPLAY INVISIBLE (1700 2175);
FORCEPROP 0 LAST CDS_LOCATION U195
J 0
(1725 2250);
DISPLAY 1.021277 (1725 2250);
DISPLAY INVISIBLE (1725 2250);
FORCEPROP 0 LAST $SEC 1
J 0
(1725 2250);
DISPLAY 0.680851 (1725 2250);
PAINT MONO (1725 2250);
DISPLAY INVISIBLE (1725 2250);
FORCEPROP 0 LAST CDS_SEC 1
J 0
(1725 2250);
DISPLAY 1.021277 (1725 2250);
DISPLAY INVISIBLE (1725 2250);
FORCEADD UNIVERSAL_POWER..1
(0 3525);
FORCEPROP 3 LASTPIN (0 3475) SIG_NAME P3V3_AUX\g
J 0
(10 3485);
DISPLAY 0.659574 (10 3485);
PAINT MONO (10 3485);
DISPLAY INVISIBLE (10 3485);
FORCEPROP 1 LAST HDL_POWER P3V3_AUX
J 1
(0 3575);
DISPLAY 0.872340 (0 3575);
PAINT GREEN (0 3575);
FORCEPROP 2 LAST CDS_LIB logical_power
J 0
(0 3525);
PAINT MONO (0 3525);
DISPLAY INVISIBLE (0 3525);
FORCEPROP 1 LAST PATH I67
J 0
(50 3550);
DISPLAY 0.872340 (50 3550);
PAINT AQUA (50 3550);
DISPLAY INVISIBLE (50 3550);
FORCEADD Q_RES..2
(0 3275);
FORCEPROP 1 LAST PART_NUMBER CS41002FB09
J 0
(40 3150);
DISPLAY 0.510638 (40 3150);
DISPLAY INVISIBLE (40 3150);
FORCEPROP 1 LAST TOLERANCE 1%
J 0
(45 3300);
DISPLAY 0.510638 (45 3300);
FORCEPROP 1 LAST WATTAGE 1/16W
J 0
(40 3250);
DISPLAY 0.510638 (40 3250);
FORCEPROP 1 LAST MATERIAL EMPTY
J 0
(40 3200);
DISPLAY 0.510638 (40 3200);
PAINT RED (40 3200);
FORCEPROP 1 LAST PACK_TYPE 0402LF
J 0
(40 3100);
DISPLAY 0.510638 (40 3100);
FORCEPROP 1 LAST VALUE 100K
J 0
(45 3350);
DISPLAY 0.510638 (45 3350);
FORCEPROP 1 LAST $LOCATION R2815
J 0
(45 3400);
DISPLAY 0.978723 (45 3400);
FORCEPROP 1 LASTPIN (0 3375) $PN 1
J 0
(5 3337);
DISPLAY 0.787234 (5 3337);
PAINT MONO (5 3337);
FORCEPROP 1 LASTPIN (0 3175) $PN 2
J 0
(5 3185);
DISPLAY 0.787234 (5 3185);
PAINT MONO (5 3185);
FORCEPROP 2 LAST CDS_LIB pure_quanta
J 0
(0 3275);
DISPLAY INVISIBLE (0 3275);
FORCEPROP 1 LAST PATH I68
J 0
(50 3450);
DISPLAY 0.978723 (50 3450);
PAINT WHITE (50 3450);
DISPLAY INVISIBLE (50 3450);
FORCEPROP 0 LAST CDS_LOCATION R2815
J 0
(50 3450);
DISPLAY 1.021277 (50 3450);
DISPLAY INVISIBLE (50 3450);
FORCEPROP 0 LAST $SEC 1
J 0
(50 3450);
DISPLAY 0.680851 (50 3450);
PAINT MONO (50 3450);
DISPLAY INVISIBLE (50 3450);
FORCEPROP 0 LAST CDS_SEC 1
J 0
(50 3450);
DISPLAY 1.021277 (50 3450);
DISPLAY INVISIBLE (50 3450);
FORCEADD UNIVERSAL_GND..1
(25 2600);
FORCEPROP 3 LASTPIN (25 2650) SIG_NAME GND\g
J 0
(35 2660);
DISPLAY 0.659574 (35 2660);
PAINT MONO (35 2660);
DISPLAY INVISIBLE (35 2660);
FORCEPROP 1 LAST PATH I69
J 0
(100 2600);
DISPLAY 0.872340 (100 2600);
PAINT AQUA (100 2600);
DISPLAY INVISIBLE (100 2600);
FORCEPROP 2 LAST CDS_LIB logical_power
J 0
(25 2600);
DISPLAY INVISIBLE (25 2600);
FORCEPROP 1 LAST HDL_POWER GND
J 1
(50 2525);
DISPLAY 0.872340 (50 2525);
PAINT GREEN (50 2525);
DISPLAY INVISIBLE (50 2525);
FORCEADD OFFPAGE..4
R 2
(-250 3000);
FORCEPROP 2 LAST $XR0 213 
J 0
(-502 3000);
DISPLAY 0.638298 (-502 3000);
PAINT MONO (-502 3000);
FORCEPROP 1 LAST OFFPAGE TRUE
J 2
(-575 2875);
DISPLAY 0.872340 (-575 2875);
PAINT GREEN (-575 2875);
DISPLAY INVISIBLE (-575 2875);
FORCEPROP 1 LAST COMMENT_BODY TRUE
J 2
(-225 2900);
DISPLAY 0.872340 (-225 2900);
PAINT GREEN (-225 2900);
DISPLAY INVISIBLE (-225 2900);
FORCEPROP 2 LAST CDS_LIB standard
J 0
(-250 3000);
DISPLAY INVISIBLE (-250 3000);
FORCEPROP 2 LAST PATH I70
J 0
(-500 3050);
DISPLAY 1.021277 (-500 3050);
DISPLAY INVISIBLE (-500 3050);
FORCEADD UNIVERSAL_POWER..1
(0 2400);
FORCEPROP 3 LASTPIN (0 2350) SIG_NAME P3V3_AUX\g
J 0
(10 2360);
DISPLAY 0.659574 (10 2360);
PAINT MONO (10 2360);
DISPLAY INVISIBLE (10 2360);
FORCEPROP 1 LAST HDL_POWER P3V3_AUX
J 1
(0 2450);
DISPLAY 0.872340 (0 2450);
PAINT GREEN (0 2450);
FORCEPROP 2 LAST CDS_LIB logical_power
J 0
(0 2400);
PAINT MONO (0 2400);
DISPLAY INVISIBLE (0 2400);
FORCEPROP 1 LAST PATH I71
J 0
(50 2425);
DISPLAY 0.872340 (50 2425);
PAINT AQUA (50 2425);
DISPLAY INVISIBLE (50 2425);
FORCEADD UNIVERSAL_GND..1
(25 1500);
FORCEPROP 3 LASTPIN (25 1550) SIG_NAME GND\g
J 0
(35 1560);
DISPLAY 0.659574 (35 1560);
PAINT MONO (35 1560);
DISPLAY INVISIBLE (35 1560);
FORCEPROP 1 LAST PATH I74
J 0
(100 1500);
DISPLAY 0.872340 (100 1500);
PAINT AQUA (100 1500);
DISPLAY INVISIBLE (100 1500);
FORCEPROP 1 LAST HDL_POWER GND
J 1
(50 1425);
DISPLAY 0.872340 (50 1425);
PAINT GREEN (50 1425);
DISPLAY INVISIBLE (50 1425);
FORCEPROP 2 LAST CDS_LIB logical_power
J 0
(25 1500);
DISPLAY INVISIBLE (25 1500);
FORCEADD OFFPAGE..4
R 2
(-200 1875);
FORCEPROP 2 LAST $XR0 227 
J 0
(-482 1875);
DISPLAY 0.638298 (-482 1875);
PAINT MONO (-482 1875);
FORCEPROP 2 LAST CDS_LIB standard
J 0
(-200 1875);
DISPLAY INVISIBLE (-200 1875);
FORCEPROP 1 LAST COMMENT_BODY TRUE
J 2
(-175 1775);
DISPLAY 0.872340 (-175 1775);
PAINT GREEN (-175 1775);
DISPLAY INVISIBLE (-175 1775);
FORCEPROP 1 LAST OFFPAGE TRUE
J 2
(-525 1750);
DISPLAY 0.872340 (-525 1750);
PAINT GREEN (-525 1750);
DISPLAY INVISIBLE (-525 1750);
FORCEPROP 2 LAST PATH I75
J 0
(-450 1925);
DISPLAY 1.021277 (-450 1925);
DISPLAY INVISIBLE (-450 1925);
FORCEADD UNIVERSAL_GND..1
(1500 1850);
FORCEPROP 3 LASTPIN (1500 1900) SIG_NAME GND\g
J 0
(1510 1910);
DISPLAY 0.659574 (1510 1910);
PAINT MONO (1510 1910);
DISPLAY INVISIBLE (1510 1910);
FORCEPROP 2 LAST CDS_LIB logical_power
J 0
(1500 1850);
DISPLAY INVISIBLE (1500 1850);
FORCEPROP 1 LAST HDL_POWER GND
J 1
(1525 1775);
DISPLAY 0.872340 (1525 1775);
PAINT GREEN (1525 1775);
DISPLAY INVISIBLE (1525 1775);
FORCEPROP 1 LAST PATH I76
J 0
(1575 1850);
DISPLAY 0.872340 (1575 1850);
PAINT AQUA (1575 1850);
DISPLAY INVISIBLE (1575 1850);
FORCEADD Q_RES..2
(2500 3225);
FORCEPROP 1 LAST PART_NUMBER CS24702JB10
J 0
(2540 3050);
DISPLAY 0.638298 (2540 3050);
DISPLAY INVISIBLE (2540 3050);
FORCEPROP 1 LAST PACK_TYPE 0402LF
J 0
(2540 3100);
DISPLAY 0.638298 (2540 3100);
FORCEPROP 1 LAST TOLERANCE 5%
J 0
(2545 3250);
DISPLAY 0.638298 (2545 3250);
FORCEPROP 1 LAST WATTAGE 1/16W
J 0
(2540 3200);
DISPLAY 0.638298 (2540 3200);
FORCEPROP 1 LAST MATERIAL EMPTY
J 0
(2540 3150);
DISPLAY 0.638298 (2540 3150);
PAINT RED (2540 3150);
FORCEPROP 1 LAST VALUE 4.7K
J 0
(2545 3300);
DISPLAY 0.638298 (2545 3300);
FORCEPROP 1 LAST $LOCATION R2820
J 0
(2545 3350);
DISPLAY 0.638298 (2545 3350);
FORCEPROP 1 LASTPIN (2500 3325) $PN 1
J 0
(2505 3287);
DISPLAY 0.787234 (2505 3287);
FORCEPROP 1 LASTPIN (2500 3125) $PN 2
J 0
(2505 3135);
DISPLAY 0.787234 (2505 3135);
FORCEPROP 1 LAST PATH I78
J 0
(2550 3400);
DISPLAY 0.978723 (2550 3400);
PAINT WHITE (2550 3400);
DISPLAY INVISIBLE (2550 3400);
FORCEPROP 2 LAST CDS_LIB pure_quanta
J 0
(2500 3225);
PAINT MONO (2500 3225);
DISPLAY INVISIBLE (2500 3225);
FORCEPROP 2 LAST CDS_LOCATION R2820
J 0
(2550 3450);
DISPLAY 1.021277 (2550 3450);
DISPLAY INVISIBLE (2550 3450);
FORCEPROP 2 LAST $SEC 1
J 0
(2550 3450);
DISPLAY 0.680851 (2550 3450);
PAINT MONO (2550 3450);
DISPLAY INVISIBLE (2550 3450);
FORCEPROP 2 LAST CDS_SEC 1
J 0
(2550 3450);
DISPLAY 1.021277 (2550 3450);
DISPLAY INVISIBLE (2550 3450);
FORCEADD OFFPAGE..2
(4125 3000);
FORCEPROP 2 LAST $XR0 140 
J 0
(4314 3000);
DISPLAY 0.638298 (4314 3000);
PAINT MONO (4314 3000);
FORCEPROP 1 LAST COMMENT_BODY TRUE
J 0
(4080 2905);
DISPLAY 0.872340 (4080 2905);
PAINT GREEN (4080 2905);
DISPLAY INVISIBLE (4080 2905);
FORCEPROP 1 LAST OFFPAGE TRUE
J 0
(4450 2875);
DISPLAY 0.872340 (4450 2875);
PAINT AQUA (4450 2875);
DISPLAY INVISIBLE (4450 2875);
FORCEPROP 2 LAST CDS_LIB standard
J 0
(4125 3000);
DISPLAY INVISIBLE (4125 3000);
FORCEPROP 2 LAST PATH I79
J 0
(4325 3050);
DISPLAY 1.021277 (4325 3050);
DISPLAY INVISIBLE (4325 3050);
FORCEADD UNIVERSAL_POWER..1
(2500 3475);
FORCEPROP 3 LASTPIN (2500 3425) SIG_NAME P3V3_AUX\g
J 0
(2510 3435);
DISPLAY 0.659574 (2510 3435);
PAINT MONO (2510 3435);
DISPLAY INVISIBLE (2510 3435);
FORCEPROP 1 LAST HDL_POWER P3V3_AUX
J 1
(2500 3525);
DISPLAY 0.872340 (2500 3525);
PAINT GREEN (2500 3525);
FORCEPROP 1 LAST PATH I80
J 0
(2550 3500);
DISPLAY 0.872340 (2550 3500);
PAINT AQUA (2550 3500);
DISPLAY INVISIBLE (2550 3500);
FORCEPROP 2 LAST CDS_LIB logical_power
J 0
(2500 3475);
PAINT MONO (2500 3475);
DISPLAY INVISIBLE (2500 3475);
FORCEADD OFFPAGE..2
(4125 1875);
FORCEPROP 2 LAST $XR0 136 
J 0
(4314 1875);
DISPLAY 0.638298 (4314 1875);
PAINT MONO (4314 1875);
FORCEPROP 2 LAST CDS_LIB standard
J 0
(4125 1875);
DISPLAY INVISIBLE (4125 1875);
FORCEPROP 1 LAST OFFPAGE TRUE
J 0
(4450 1750);
DISPLAY 0.872340 (4450 1750);
PAINT AQUA (4450 1750);
DISPLAY INVISIBLE (4450 1750);
FORCEPROP 1 LAST COMMENT_BODY TRUE
J 0
(4080 1780);
DISPLAY 0.872340 (4080 1780);
PAINT GREEN (4080 1780);
DISPLAY INVISIBLE (4080 1780);
FORCEPROP 2 LAST PATH I82
J 0
(4325 1925);
DISPLAY 1.021277 (4325 1925);
DISPLAY INVISIBLE (4325 1925);
FORCEADD UNIVERSAL_POWER..1
(2600 2300);
FORCEPROP 3 LASTPIN (2600 2250) SIG_NAME P3V3_AUX\g
J 0
(2610 2260);
DISPLAY 0.659574 (2610 2260);
PAINT MONO (2610 2260);
DISPLAY INVISIBLE (2610 2260);
FORCEPROP 1 LAST HDL_POWER P3V3_AUX
J 1
(2600 2350);
DISPLAY 0.872340 (2600 2350);
PAINT GREEN (2600 2350);
FORCEPROP 1 LAST PATH I83
J 0
(2650 2325);
DISPLAY 0.872340 (2650 2325);
PAINT AQUA (2650 2325);
DISPLAY INVISIBLE (2650 2325);
FORCEPROP 2 LAST CDS_LIB logical_power
J 0
(2600 2300);
PAINT MONO (2600 2300);
DISPLAY INVISIBLE (2600 2300);
FORCEADD UNIVERSAL_POWER..1
(1625 3700);
FORCEPROP 3 LASTPIN (1625 3650) SIG_NAME P3V3_AUX\g
J 0
(1635 3660);
DISPLAY 0.659574 (1635 3660);
PAINT MONO (1635 3660);
DISPLAY INVISIBLE (1635 3660);
FORCEPROP 1 LAST HDL_POWER P3V3_AUX
J 1
(1625 3750);
DISPLAY 0.872340 (1625 3750);
PAINT GREEN (1625 3750);
FORCEPROP 2 LAST CDS_LIB logical_power
J 0
(1625 3700);
PAINT MONO (1625 3700);
DISPLAY INVISIBLE (1625 3700);
FORCEPROP 1 LAST PATH I87
J 0
(1675 3725);
DISPLAY 0.872340 (1675 3725);
PAINT AQUA (1675 3725);
DISPLAY INVISIBLE (1675 3725);
FORCEADD UNIVERSAL_GND..1
(1625 3150);
FORCEPROP 3 LASTPIN (1625 3200) SIG_NAME GND\g
J 0
(1635 3210);
DISPLAY 0.659574 (1635 3210);
PAINT MONO (1635 3210);
DISPLAY INVISIBLE (1635 3210);
FORCEPROP 2 LAST CDS_LIB logical_power
J 0
(1625 3150);
PAINT MONO (1625 3150);
DISPLAY INVISIBLE (1625 3150);
FORCEPROP 1 LAST HDL_POWER GND
J 1
(1650 3075);
DISPLAY 0.872340 (1650 3075);
PAINT GREEN (1650 3075);
DISPLAY INVISIBLE (1650 3075);
FORCEPROP 1 LAST PATH I88
J 0
(1700 3150);
DISPLAY 0.872340 (1700 3150);
PAINT AQUA (1700 3150);
DISPLAY INVISIBLE (1700 3150);
FORCEADD Q_CAP..1
(1625 3375);
FORCEPROP 1 LAST PART_NUMBER CH4104K1B00
J 0
(1675 3225);
DISPLAY 0.510638 (1675 3225);
DISPLAY INVISIBLE (1675 3225);
FORCEPROP 1 LAST VALUE 0.1UF
J 0
(1675 3425);
DISPLAY 0.510638 (1675 3425);
FORCEPROP 1 LAST VOLTAGE 25V
J 0
(1675 3375);
DISPLAY 0.510638 (1675 3375);
FORCEPROP 1 LAST TOLERANCE 10%
J 0
(1675 3325);
DISPLAY 0.510638 (1675 3325);
FORCEPROP 1 LAST MATERIAL X7R
J 0
(1675 3275);
DISPLAY 0.510638 (1675 3275);
FORCEPROP 1 LAST PACK_TYPE 0402
J 0
(1675 3175);
DISPLAY 0.510638 (1675 3175);
FORCEPROP 1 LAST $LOCATION C1769
J 0
(1675 3475);
DISPLAY 0.787234 (1675 3475);
FORCEPROP 1 LASTPIN (1625 3475) $PN 1
J 0
(1635 3455);
DISPLAY 0.787234 (1635 3455);
FORCEPROP 1 LASTPIN (1625 3275) $PN 2
J 0
(1635 3255);
DISPLAY 0.787234 (1635 3255);
FORCEPROP 2 LAST CDS_LIB pure_quanta
J 2
(1625 3375);
PAINT MONO (1625 3375);
DISPLAY INVISIBLE (1625 3375);
FORCEPROP 1 LAST PATH I89
J 0
(1675 3525);
DISPLAY 0.978723 (1675 3525);
PAINT WHITE (1675 3525);
DISPLAY INVISIBLE (1675 3525);
FORCEPROP 2 LAST CDS_LOCATION C1769
J 0
(1675 3575);
DISPLAY 1.021277 (1675 3575);
DISPLAY INVISIBLE (1675 3575);
FORCEPROP 2 LAST $SEC 1
J 0
(1675 3575);
DISPLAY 0.680851 (1675 3575);
PAINT MONO (1675 3575);
DISPLAY INVISIBLE (1675 3575);
FORCEPROP 2 LAST CDS_SEC 1
J 0
(1675 3575);
DISPLAY 1.021277 (1675 3575);
DISPLAY INVISIBLE (1675 3575);
FORCEADD Q_RES..2
(25 2800);
FORCEPROP 1 LAST PART_NUMBER CS24702JB10
J 0
(65 2625);
DISPLAY 0.638298 (65 2625);
DISPLAY INVISIBLE (65 2625);
FORCEPROP 1 LAST PACK_TYPE 0402LF
J 0
(65 2675);
DISPLAY 0.638298 (65 2675);
FORCEPROP 1 LAST VALUE 4.7K
J 0
(70 2875);
DISPLAY 0.638298 (70 2875);
FORCEPROP 1 LAST TOLERANCE 5%
J 0
(70 2825);
DISPLAY 0.638298 (70 2825);
FORCEPROP 1 LAST WATTAGE 1/16W
J 0
(65 2775);
DISPLAY 0.638298 (65 2775);
FORCEPROP 1 LAST MATERIAL CHIP
J 0
(65 2725);
DISPLAY 0.638298 (65 2725);
FORCEPROP 1 LAST $LOCATION R2915
J 0
(70 2925);
DISPLAY 0.638298 (70 2925);
FORCEPROP 1 LASTPIN (25 2900) $PN 1
J 0
(30 2862);
DISPLAY 0.787234 (30 2862);
FORCEPROP 1 LASTPIN (25 2700) $PN 2
J 0
(30 2710);
DISPLAY 0.787234 (30 2710);
FORCEPROP 1 LAST PATH I92
J 0
(75 2975);
DISPLAY 0.978723 (75 2975);
PAINT WHITE (75 2975);
DISPLAY INVISIBLE (75 2975);
FORCEPROP 2 LAST CDS_LIB pure_quanta
J 0
(25 2800);
PAINT MONO (25 2800);
DISPLAY INVISIBLE (25 2800);
FORCEPROP 2 LAST CDS_LOCATION R2915
J 0
(75 3025);
DISPLAY 1.021277 (75 3025);
DISPLAY INVISIBLE (75 3025);
FORCEPROP 2 LAST $SEC 1
J 0
(75 3025);
DISPLAY 0.680851 (75 3025);
PAINT MONO (75 3025);
DISPLAY INVISIBLE (75 3025);
FORCEPROP 2 LAST CDS_SEC 1
J 0
(75 3025);
DISPLAY 1.021277 (75 3025);
DISPLAY INVISIBLE (75 3025);
FORCEADD Q_RES..2
(25 1675);
FORCEPROP 1 LAST PART_NUMBER CS24702JB10
J 0
(65 1500);
DISPLAY 0.638298 (65 1500);
DISPLAY INVISIBLE (65 1500);
FORCEPROP 1 LAST TOLERANCE 5%
J 0
(70 1700);
DISPLAY 0.638298 (70 1700);
FORCEPROP 1 LAST PACK_TYPE 0402LF
J 0
(65 1550);
DISPLAY 0.638298 (65 1550);
FORCEPROP 1 LAST MATERIAL EMPTY
J 0
(65 1600);
DISPLAY 0.638298 (65 1600);
PAINT RED (65 1600);
FORCEPROP 1 LAST WATTAGE 1/16W
J 0
(65 1650);
DISPLAY 0.638298 (65 1650);
FORCEPROP 1 LAST VALUE 4.7K
J 0
(70 1750);
DISPLAY 0.638298 (70 1750);
FORCEPROP 1 LAST $LOCATION R2916
J 0
(70 1800);
DISPLAY 0.638298 (70 1800);
FORCEPROP 1 LASTPIN (25 1775) $PN 1
J 0
(30 1737);
DISPLAY 0.787234 (30 1737);
FORCEPROP 1 LASTPIN (25 1575) $PN 2
J 0
(30 1585);
DISPLAY 0.787234 (30 1585);
FORCEPROP 2 LAST CDS_LIB pure_quanta
J 0
(25 1675);
PAINT MONO (25 1675);
DISPLAY INVISIBLE (25 1675);
FORCEPROP 1 LAST PATH I93
J 0
(75 1850);
DISPLAY 0.978723 (75 1850);
PAINT WHITE (75 1850);
DISPLAY INVISIBLE (75 1850);
FORCEPROP 2 LAST CDS_LOCATION R2916
J 0
(75 1900);
DISPLAY 1.021277 (75 1900);
DISPLAY INVISIBLE (75 1900);
FORCEPROP 2 LAST $SEC 1
J 0
(75 1900);
DISPLAY 0.680851 (75 1900);
PAINT MONO (75 1900);
DISPLAY INVISIBLE (75 1900);
FORCEPROP 2 LAST CDS_SEC 1
J 0
(75 1900);
DISPLAY 1.021277 (75 1900);
DISPLAY INVISIBLE (75 1900);
FORCEADD QUANTA_TITLE_BLOCK_C..1
(6375 -2675);
FORCEPROP 0 LAST CDS_CON_LAST_MODIFIED Fri Aug 25 14:02:13 2023
J 0
(4490 -2660);
PAINT MONO (4490 -2660);
DISPLAY INVISIBLE (4490 -2660);
FORCEPROP 1 LAST CUSTOM_TXT_CDS <CON_LAST_MODIFIED>
J 0
(4490 -2660);
DISPLAY 0.978723 (4490 -2660);
FORCEPROP 2 LAST CUSTOM_TXT_CDS <XR_PAGE_TITLE>
J 0
(-1515 2575);
DISPLAY 0.638298 (-1515 2575);
PAINT PINK (-1515 2575);
DISPLAY INVISIBLE (-1515 2575);
FORCEPROP 2 LAST CUSTOM_TXT_CDS <Q_NUMBER>
J 0
(4972 -2572);
DISPLAY 1.212766 (4972 -2572);
FORCEPROP 1 LAST CUSTOM_TXT_CDS <NAME_2>
J 0
(3200 -2625);
FORCEPROP 1 LAST CUSTOM_TXT_CDS <NAME_1>
J 0
(3200 -2500);
FORCEPROP 1 LAST CUSTOM_TXT_CDS <Q_PROJ>
J 0
(3993 -2573);
DISPLAY 1.212766 (3993 -2573);
FORCEPROP 1 LAST CUSTOM_TXT_CDS <Q_REV>
J 0
(6191 -2572);
DISPLAY 1.212766 (6191 -2572);
FORCEPROP 1 LAST CUSTOM_TXT_CDS <CON_PAGE_NUM> OF <CON_TOTAL_PAGES>
J 0
(5929 -2657);
DISPLAY 0.978723 (5929 -2657);
FORCEPROP 1 LAST Q_TITLE EXAMAX_ISO (7/7)
J 0
(-2991 -2649);
DISPLAY 1.957447 (-2991 -2649);
PAINT GREEN (-2991 -2649);
FORCEPROP 1 LAST Q_DEPT 
J 1
(2612 -2626);
DISPLAY 1.957447 (2612 -2626);
PAINT GREEN (2612 -2626);
FORCEPROP 2 LAST CDS_XR_PAGE_TITLE CR-151 : @S9S_MB_2U_LIB.S9S_MB_2U(SCH_1):PAGE151
J 0
(-1515 2575);
DISPLAY 0.638298 (-1515 2575);
PAINT PINK (-1515 2575);
DISPLAY INVISIBLE (-1515 2575);
FORCEPROP 2 LAST PAGE_BORDER TRUE
J 0
(-1515 2575);
DISPLAY 0.638298 (-1515 2575);
PAINT PINK (-1515 2575);
DISPLAY INVISIBLE (-1515 2575);
FORCEPROP 1 LAST COMMENT_BODY TRUE
J 0
(6387 -2688);
DISPLAY 0.978723 (6387 -2688);
PAINT GREEN (6387 -2688);
DISPLAY INVISIBLE (6387 -2688);
FORCEPROP 1 LAST CDS_LMAN_SYM_OUTLINE -9475,6775,100,-125
J 0
(6375 -2675);
DISPLAY 0.468085 (6375 -2675);
PAINT GREEN (6375 -2675);
DISPLAY INVISIBLE (6375 -2675);
FORCEPROP 2 LAST CDS_LIB pure_quanta
J 0
(6375 -2675);
PAINT MONO (6375 -2675);
DISPLAY INVISIBLE (6375 -2675);
FORCEADD DNS..2
(400 -1600);
PAINT RED (400 -1600);
FORCEPROP 1 LAST COMMENT_BODY TRUE
J 0
(400 -1600);
DISPLAY INVISIBLE (400 -1600);
FORCEPROP 2 LAST CDS_LIB mstr_misc
J 0
(400 -1600);
DISPLAY INVISIBLE (400 -1600);
FORCEADD DNS..2
(0 -275);
PAINT RED (0 -275);
FORCEPROP 2 LAST CDS_LIB mstr_misc
J 0
(0 -275);
DISPLAY INVISIBLE (0 -275);
FORCEPROP 1 LAST COMMENT_BODY TRUE
J 0
(0 -275);
DISPLAY INVISIBLE (0 -275);
FORCEADD DNS..2
(2600 2025);
PAINT RED (2600 2025);
FORCEPROP 1 LAST COMMENT_BODY TRUE
J 0
(2600 2025);
DISPLAY INVISIBLE (2600 2025);
FORCEPROP 2 LAST CDS_LIB mstr_misc
J 0
(2600 2025);
DISPLAY INVISIBLE (2600 2025);
FORCEADD DNS..2
(2500 3200);
PAINT RED (2500 3200);
FORCEPROP 1 LAST COMMENT_BODY TRUE
J 0
(2500 3200);
DISPLAY INVISIBLE (2500 3200);
FORCEPROP 2 LAST CDS_LIB mstr_misc
J 0
(2500 3200);
DISPLAY INVISIBLE (2500 3200);
FORCEADD DNS..2
(2575 825);
PAINT RED (2575 825);
FORCEPROP 2 LAST CDS_LIB mstr_misc
J 0
(2575 825);
DISPLAY INVISIBLE (2575 825);
FORCEPROP 1 LAST COMMENT_BODY TRUE
J 0
(2575 825);
DISPLAY INVISIBLE (2575 825);
FORCEADD DNS..2
(2650 -350);
PAINT RED (2650 -350);
FORCEPROP 1 LAST COMMENT_BODY TRUE
J 0
(2650 -350);
DISPLAY INVISIBLE (2650 -350);
FORCEPROP 2 LAST CDS_LIB mstr_misc
J 0
(2650 -350);
DISPLAY INVISIBLE (2650 -350);
FORCEADD DNS..2
(0 3250);
PAINT RED (0 3250);
FORCEPROP 1 LAST COMMENT_BODY TRUE
J 0
(0 3250);
DISPLAY INVISIBLE (0 3250);
FORCEPROP 2 LAST CDS_LIB mstr_misc
J 0
(0 3250);
DISPLAY INVISIBLE (0 3250);
FORCEADD DNS..2
(25 1650);
PAINT RED (25 1650);
FORCEPROP 2 LAST CDS_LIB mstr_misc
J 0
(25 1650);
DISPLAY INVISIBLE (25 1650);
FORCEPROP 1 LAST COMMENT_BODY TRUE
J 0
(25 1650);
DISPLAY INVISIBLE (25 1650);
FORCEADD DNS..2
(-75 850);
PAINT RED (-75 850);
FORCEPROP 2 LAST CDS_LIB mstr_misc
J 0
(-75 850);
DISPLAY INVISIBLE (-75 850);
FORCEPROP 1 LAST COMMENT_BODY TRUE
J 0
(-75 850);
DISPLAY INVISIBLE (-75 850);
WIRE 16 -1 (400 -1300)(400 -1475);
WIRE 16 -1 (-325 -1100)(-325 -1175);
WIRE 16 -1 (0 -50)(0 -150);
WIRE 16 -1 (-1900 -1250)(-1900 -1425);
WIRE 16 -1 (0 2350)(0 2250);
WIRE 16 -1 (2600 2250)(2600 2150);
WIRE 16 -1 (2650 -125)(2650 -225);
WIRE 16 -1 (1625 1250)(1625 1175);
WIRE 16 -1 (2575 1050)(2575 950);
WIRE 16 -1 (2500 3425)(2500 3325);
WIRE 16 -1 (0 3475)(0 3375);
WIRE 16 -1 (-75 1075)(-75 975);
WIRE 16 -1 (1625 3650)(1625 3575);
WIRE 16 -1 (-550 -2150)(-550 -2250);
WIRE 16 -1 (-325 -1475)(-325 -1550);
WIRE 16 -1 (2525 2600)(2525 2525);
WIRE 16 -1 (2625 1475)(2625 1400);
WIRE 16 -1 (2625 225)(2625 150);
WIRE 16 -1 (1625 3275)(1625 3200);
WIRE 16 -1 (1500 2025)(1500 1900);
WIRE 16 -1 (1625 875)(1625 800);
WIRE 16 -1 (2650 -900)(2650 -975);
WIRE 16 -1 (1500 -375)(1500 -500);
WIRE 16 -1 (25 -825)(25 -850);
WIRE 16 -1 (25 2650)(25 2700);
WIRE 16 -1 (25 1550)(25 1575);
WIRE 16 -1 (-50 300)(-50 275);
WIRE 16 -1 (-1475 -1850)(-800 -1850);
FORCEPROP 2 LAST SIG_NAME UART_BMC_BIC_R_RX
J 0
(-1360 -1840);
DISPLAY 0.638298 (-1360 -1840);
PAINT WHITE (-1360 -1840);
WIRE 16 2175 (-2075 -1075)(-1600 -1075);
WIRE 16 2175 (-1600 -1075)(-1600 -1725);
WIRE 16 2175 (-2075 -1075)(-2075 -1725);
WIRE 16 2175 (-2075 -1725)(-1600 -1725);
WIRE 16 2175 (250 -1375)(750 -1375);
WIRE 16 2175 (750 -1375)(750 -1775);
WIRE 16 2175 (250 -1375)(250 -1775);
WIRE 16 2175 (250 -1775)(750 -1775);
WIRE 16 -1 (400 -1900)(-300 -1900);
FORCEPROP 2 LAST SIG_NAME UART_BMC_BIC_R_BUF_RX
J 0
(-235 -1890);
DISPLAY 0.638298 (-235 -1890);
PAINT WHITE (-235 -1890);
WIRE 16 -1 (400 -1675)(400 -1900);
WIRE 16 -1 (550 -1900)(400 -1900);
WIRE 16 2175 (425 -1800)(925 -1800);
WIRE 16 2175 (925 -1800)(925 -2000);
WIRE 16 2175 (425 -1800)(425 -2000);
WIRE 16 2175 (425 -2000)(925 -2000);
WIRE 16 -1 (750 -1900)(2075 -1900);
FORCEPROP 2 LAST SIG_NAME UART_BMC_BIC_BUF_RX
J 0
(940 -1890);
DISPLAY 0.723404 (940 -1890);
PAINT WHITE (940 -1890);
WIRE 16 -1 (-325 -1175)(-325 -1275);
WIRE 16 -1 (-325 -1175)(-550 -1175);
WIRE 16 -1 (-550 -1650)(-550 -1175);
WIRE 16 -1 (-2550 -1950)(-1675 -1950);
FORCEPROP 2 LAST SIG_NAME FM_PDB_BUF_EN_R
J 0
(-2510 -1940);
DISPLAY 0.723404 (-2510 -1940);
PAINT WHITE (-2510 -1940);
WIRE 16 -1 (1100 -75)(1100 -525);
WIRE 16 -1 (25 -625)(25 -525);
WIRE 16 -1 (25 -525)(1100 -525);
FORCEPROP 2 LAST SIG_NAME GPU_FPGA_RST_R_N
J 0
(65 -515);
DISPLAY 0.808511 (65 -515);
WIRE 16 -1 (25 -525)(0 -525);
WIRE 16 -1 (0 -350)(0 -525);
WIRE 16 -1 (0 -525)(-150 -525);
WIRE 16 -1 (3000 -525)(3925 -525);
FORCEPROP 2 LAST SIG_NAME GPU_FPGA_RST_R_BUF_N
J 0
(3165 -515);
DISPLAY 0.808511 (3165 -515);
WIRE 16 -1 (-1475 -1950)(-800 -1950);
FORCEPROP 2 LAST SIG_NAME FM_UART_EN
J 0
(-1360 -1940);
DISPLAY 0.723404 (-1360 -1940);
PAINT WHITE (-1360 -1940);
WIRE 16 -1 (1625 3575)(1625 3475);
WIRE 16 -1 (1625 3575)(1500 3575);
WIRE 16 -1 (1500 2875)(1500 3575);
WIRE 16 -1 (1625 1175)(1625 1075);
WIRE 16 -1 (1625 1175)(1500 1175);
WIRE 16 -1 (1500 475)(1500 1175);
WIRE 16 -1 (-2550 -1850)(-1900 -1850);
FORCEPROP 2 LAST SIG_NAME UART_BMC_BIC_RX
J 0
(-2510 -1840);
DISPLAY 0.723404 (-2510 -1840);
PAINT WHITE (-2510 -1840);
WIRE 16 -1 (-1900 -1850)(-1675 -1850);
WIRE 16 -1 (-1900 -1625)(-1900 -1850);
WIRE 16 -1 (1850 -525)(1850 -75);
WIRE 16 -1 (1850 -525)(2650 -525);
FORCEPROP 2 LAST SIG_NAME GPU_FPGA_RST_R1_BUF_N
J 0
(1840 -515);
DISPLAY 0.808511 (1840 -515);
WIRE 16 -1 (2650 -525)(2800 -525);
WIRE 16 -1 (2650 -425)(2650 -525);
WIRE 16 -1 (2650 -700)(2650 -525);
WIRE 16 -1 (1850 1875)(1850 2325);
WIRE 16 -1 (1850 1875)(2600 1875);
FORCEPROP 2 LAST SIG_NAME RST_SWB_BIC_BUF_R_N
J 0
(1865 1885);
DISPLAY 0.638298 (1865 1885);
WIRE 16 -1 (2600 1950)(2600 1875);
WIRE 16 -1 (2600 1875)(2625 1875);
WIRE 16 -1 (2625 1875)(2825 1875);
WIRE 16 -1 (2625 1675)(2625 1875);
WIRE 16 2175 (-175 1475)(650 1475);
WIRE 16 2175 (650 2525)(650 1475);
WIRE 16 2175 (-175 2525)(-175 1475);
WIRE 16 2175 (-175 2525)(650 2525);
WIRE 16 -1 (1850 3000)(1850 2575);
WIRE 16 -1 (1850 3000)(2500 3000);
FORCEPROP 2 LAST SIG_NAME BMC_MONITER_BUF_R
J 0
(1865 3010);
DISPLAY 0.638298 (1865 3010);
WIRE 16 -1 (2500 3125)(2500 3000);
WIRE 16 -1 (2500 3000)(2525 3000);
WIRE 16 -1 (2525 3000)(2750 3000);
WIRE 16 -1 (2525 2800)(2525 3000);
WIRE 16 2175 (2425 1325)(3200 1325);
WIRE 16 2175 (3200 2400)(3200 1325);
WIRE 16 2175 (2425 2400)(2425 1325);
WIRE 16 2175 (2425 2400)(3200 2400);
WIRE 16 -1 (4075 1875)(3025 1875);
FORCEPROP 2 LAST SIG_NAME RST_SWB_BIC_BUF_N
J 0
(3340 1885);
DISPLAY 0.808511 (3340 1885);
WIRE 16 -1 (4075 3000)(2950 3000);
FORCEPROP 2 LAST SIG_NAME BMC_MONITER_BUF
J 0
(3265 3010);
DISPLAY 0.808511 (3265 3010);
WIRE 16 -1 (1100 2325)(1100 1875);
WIRE 16 -1 (25 1775)(25 1875);
WIRE 16 -1 (25 1875)(1100 1875);
FORCEPROP 2 LAST SIG_NAME RST_SWB_BIC_R_N
J 0
(65 1885);
DISPLAY 0.808511 (65 1885);
WIRE 16 -1 (25 1875)(0 1875);
WIRE 16 -1 (0 2050)(0 1875);
WIRE 16 -1 (0 1875)(-150 1875);
WIRE 16 -1 (3875 600)(2925 600);
FORCEPROP 2 LAST SIG_NAME FM_GPU_PWR_EN_R_BUF
J 0
(3115 610);
DISPLAY 0.808511 (3115 610);
WIRE 16 -1 (1850 600)(1850 175);
WIRE 16 -1 (2575 600)(1850 600);
FORCEPROP 2 LAST SIG_NAME FM_GPU_PWR_EN_R1
J 0
(1890 610);
DISPLAY 0.808511 (1890 610);
WIRE 16 -1 (2575 750)(2575 600);
WIRE 16 -1 (2575 600)(2625 600);
WIRE 16 -1 (2625 600)(2725 600);
WIRE 16 -1 (2625 425)(2625 600);
WIRE 16 -1 (1100 3000)(1100 2575);
WIRE 16 -1 (25 2900)(25 3000);
WIRE 16 -1 (1100 3000)(25 3000);
FORCEPROP 2 LAST SIG_NAME BMC_MONITER_R
J 0
(65 3010);
DISPLAY 0.808511 (65 3010);
WIRE 16 -1 (25 3000)(0 3000);
WIRE 16 -1 (0 3175)(0 3000);
WIRE 16 -1 (0 3000)(-200 3000);
WIRE 16 -1 (-200 600)(-75 600);
WIRE 16 -1 (-75 600)(-75 775);
WIRE 16 -1 (-50 500)(-50 600);
WIRE 16 -1 (-75 600)(-50 600);
WIRE 16 -1 (-50 600)(1100 600);
FORCEPROP 2 LAST SIG_NAME FM_GPU_PWR_EN_R
J 0
(65 610);
DISPLAY 0.808511 (65 610);
WIRE 16 -1 (1100 600)(1100 175);
DOT 1 (-325 -1175);
DOT 1 (400 -1900);
DOT 1 (-1900 -1850);
DOT 1 (2525 3000);
DOT 1 (2500 3000);
DOT 1 (2625 1875);
DOT 1 (2625 600);
DOT 1 (2575 600);
DOT 1 (1625 3575);
DOT 1 (25 3000);
DOT 1 (1625 1175);
DOT 1 (25 1875);
DOT 1 (2650 -525);
DOT 1 (25 -525);
DOT 1 (0 3000);
DOT 1 (0 1875);
DOT 1 (-50 600);
DOT 1 (-75 600);
DOT 1 (0 -525);
DOT 1 (2600 1875);
FORCENOTE
20211215 ADD R4515 PU TO P3V3_AUX
(-2375 -1050) 0;
DISPLAY LEFT (-2375 -1050);
DISPLAY 1.063830 (-2375 -1050);
PAINT WHITE (-2375 -1050);
FORCENOTE
PUSH-PULL OUTPUT
(1150 -850) 0;
DISPLAY LEFT (1150 -850);
DISPLAY 1.021277 (1150 -850);
PAINT WHITE (1150 -850);
FORCENOTE
20210527 MODIFY FOR GT
(-2875 3775) 0;
DISPLAY LEFT (-2875 3775);
DISPLAY 2.510638 (-2875 3775);
PAINT PINK (-2875 3775);
FORCENOTE
PUSH-PULL OUTPUT
(1100 1500) 0;
DISPLAY LEFT (1100 1500);
DISPLAY 1.021277 (1100 1500);
PAINT WHITE (1100 1500);
FORCENOTE
20211126 DPPOP R259,R260
(-625 1350) 0;
DISPLAY LEFT (-625 1350);
DISPLAY 1.680851 (-625 1350);
PAINT WHITE (-625 1350);
FORCENOTE
PUSH-PULL OUTPUT
(-925 -2425) 0;
DISPLAY LEFT (-925 -2425);
DISPLAY 1.021277 (-925 -2425);
PAINT WHITE (-925 -2425);
FORCENOTE
20220805 DEPOP R4173
(450 -1350) 0;
DISPLAY LEFT (450 -1350);
DISPLAY 1.063830 (450 -1350);
PAINT WHITE (450 -1350);
FORCENOTE
20211126 CHANGE R3036 TO 33.2 OHM
(125 -2125) 0;
DISPLAY LEFT (125 -2125);
DISPLAY 1.063830 (125 -2125);
PAINT WHITE (125 -2125);
QUIT
